FILE_TYPE = MACRO_DRAWING;
SET COLOR_WIRE YELLOW;
SET COLOR_PROP MONO;
SET COLOR_DOT WHITE;
SET COLOR_ARC YELLOW;
SET COLOR_BODY GREEN;
SET COLOR_NOTE MONO;
SET PROP_DISPLAY VALUE;
SET PAGE_NUMBER P56;
FORCEADD OFFPAGE..4
(-1575 2850);
FORCEPROP 2 LAST $XR0 111 
J 0
(-1389 2850);
DISPLAY 0.638298 (-1389 2850);
PAINT MONO (-1389 2850);
FORCEPROP 2 LAST $XR1 118 
J 0
(-1269 2850);
DISPLAY 0.638298 (-1269 2850);
PAINT MONO (-1269 2850);
FORCEPROP 2 LAST $XR2 22 
J 0
(-1149 2850);
DISPLAY 0.638298 (-1149 2850);
PAINT MONO (-1149 2850);
FORCEPROP 2 LAST CDS_LIB mstr_standard
J 0
(-1575 2850);
DISPLAY 0.787234 (-1575 2850);
PAINT MONO (-1575 2850);
DISPLAY INVISIBLE (-1575 2850);
FORCEPROP 1 LAST OFFPAGE TRUE
J 0
(-1250 2725);
DISPLAY 0.680851 (-1250 2725);
PAINT GREEN (-1250 2725);
DISPLAY INVISIBLE (-1250 2725);
FORCEPROP 1 LAST COMMENT_BODY TRUE
J 0
(-1600 2750);
DISPLAY 0.680851 (-1600 2750);
PAINT PEACH (-1600 2750);
DISPLAY INVISIBLE (-1600 2750);
FORCEPROP 2 LAST PATH I161
J 0
(-1250 2900);
DISPLAY 1.021277 (-1250 2900);
PAINT ORANGE (-1250 2900);
DISPLAY INVISIBLE (-1250 2900);
FORCEADD OFFPAGE..4
(-1550 2450);
FORCEPROP 2 LAST $XR0 111 
J 0
(-1364 2450);
DISPLAY 0.638298 (-1364 2450);
PAINT MONO (-1364 2450);
FORCEPROP 2 LAST $XR1 22 
J 0
(-1244 2450);
DISPLAY 0.638298 (-1244 2450);
PAINT MONO (-1244 2450);
FORCEPROP 2 LAST CDS_LIB mstr_standard
J 0
(-1550 2450);
DISPLAY 0.787234 (-1550 2450);
PAINT MONO (-1550 2450);
DISPLAY INVISIBLE (-1550 2450);
FORCEPROP 1 LAST OFFPAGE TRUE
J 0
(-1225 2325);
DISPLAY 0.680851 (-1225 2325);
PAINT GREEN (-1225 2325);
DISPLAY INVISIBLE (-1225 2325);
FORCEPROP 1 LAST COMMENT_BODY TRUE
J 0
(-1575 2350);
DISPLAY 0.680851 (-1575 2350);
PAINT PEACH (-1575 2350);
DISPLAY INVISIBLE (-1575 2350);
FORCEPROP 2 LAST PATH I164
J 0
(-1225 2500);
DISPLAY 1.021277 (-1225 2500);
PAINT ORANGE (-1225 2500);
DISPLAY INVISIBLE (-1225 2500);
FORCEADD SKX_EXT_B..2
(-4025 2550);
FORCEPROP 1 LAST LOCATION U2D1
J 0
(-5225 4600);
DISPLAY 0.617021 (-5225 4600);
PAINT AQUA (-5225 4600);
FORCEPROP 1 LAST PART_NUMBER TBD
J 0
(-5225 550);
DISPLAY 0.617021 (-5225 550);
PAINT BLUE (-5225 550);
FORCEPROP 1 LAST MATERIAL IC
J 0
(-5225 4550);
DISPLAY 0.617021 (-5225 4550);
PAINT SKYBLUE (-5225 4550);
FORCEPROP 2 LASTPIN (-5275 1600) $PN AY13
J 2
(-5285 1610);
DISPLAY 0.617021 (-5285 1610);
PAINT ORANGE (-5285 1610);
FORCEPROP 2 LASTPIN (-2775 2350) $PN AN14
J 0
(-2765 2360);
DISPLAY 0.617021 (-2765 2360);
PAINT ORANGE (-2765 2360);
FORCEPROP 2 LASTPIN (-2775 2950) $PN AN12
J 0
(-2765 2960);
DISPLAY 0.617021 (-2765 2960);
PAINT ORANGE (-2765 2960);
FORCEPROP 2 LASTPIN (-2775 3000) $PN AM13
J 0
(-2765 3010);
DISPLAY 0.617021 (-2765 3010);
PAINT ORANGE (-2765 3010);
FORCEPROP 2 LASTPIN (-2775 3050) $PN AG46
J 0
(-2765 3060);
DISPLAY 0.617021 (-2765 3060);
PAINT ORANGE (-2765 3060);
FORCEPROP 2 LASTPIN (-2775 3100) $PN AF45
J 0
(-2765 3110);
DISPLAY 0.617021 (-2765 3110);
PAINT ORANGE (-2765 3110);
FORCEPROP 2 LASTPIN (-5275 4350) $PN A4
J 2
(-5285 4360);
DISPLAY 0.617021 (-5285 4360);
PAINT ORANGE (-5285 4360);
FORCEPROP 2 LASTPIN (-5275 4300) $PN A6
J 2
(-5285 4310);
DISPLAY 0.617021 (-5285 4310);
PAINT ORANGE (-5285 4310);
FORCEPROP 2 LASTPIN (-5275 4250) $PN A14
J 2
(-5285 4260);
DISPLAY 0.617021 (-5285 4260);
PAINT ORANGE (-5285 4260);
FORCEPROP 2 LASTPIN (-5275 4200) $PN A16
J 2
(-5285 4210);
DISPLAY 0.617021 (-5285 4210);
PAINT ORANGE (-5285 4210);
FORCEPROP 2 LASTPIN (-5275 4150) $PN A24
J 2
(-5285 4160);
DISPLAY 0.617021 (-5285 4160);
PAINT ORANGE (-5285 4160);
FORCEPROP 2 LASTPIN (-5275 4100) $PN B3
J 2
(-5285 4110);
DISPLAY 0.617021 (-5285 4110);
PAINT ORANGE (-5285 4110);
FORCEPROP 2 LASTPIN (-5275 4050) $PN B7
J 2
(-5285 4060);
DISPLAY 0.617021 (-5285 4060);
PAINT ORANGE (-5285 4060);
FORCEPROP 2 LASTPIN (-5275 3950) $PN B13
J 2
(-5285 3960);
DISPLAY 0.617021 (-5285 3960);
PAINT ORANGE (-5285 3960);
FORCEPROP 2 LASTPIN (-5275 3900) $PN B15
J 2
(-5285 3910);
DISPLAY 0.617021 (-5285 3910);
PAINT ORANGE (-5285 3910);
FORCEPROP 2 LASTPIN (-5275 3850) $PN B17
J 2
(-5285 3860);
DISPLAY 0.617021 (-5285 3860);
PAINT ORANGE (-5285 3860);
FORCEPROP 2 LASTPIN (-5275 3800) $PN B77
J 2
(-5285 3810);
DISPLAY 0.617021 (-5285 3810);
PAINT ORANGE (-5285 3810);
FORCEPROP 2 LASTPIN (-5275 3750) $PN B81
J 2
(-5285 3760);
DISPLAY 0.617021 (-5285 3760);
PAINT ORANGE (-5285 3760);
FORCEPROP 2 LASTPIN (-5275 3700) $PN C6
J 2
(-5285 3710);
DISPLAY 0.617021 (-5285 3710);
PAINT ORANGE (-5285 3710);
FORCEPROP 2 LASTPIN (-5275 3650) $PN C18
J 2
(-5285 3660);
DISPLAY 0.617021 (-5285 3660);
PAINT ORANGE (-5285 3660);
FORCEPROP 2 LASTPIN (-5275 3550) $PN C24
J 2
(-5285 3560);
DISPLAY 0.617021 (-5285 3560);
PAINT ORANGE (-5285 3560);
FORCEPROP 2 LASTPIN (-5275 3500) $PN C82
J 2
(-5285 3510);
DISPLAY 0.617021 (-5285 3510);
PAINT ORANGE (-5285 3510);
FORCEPROP 2 LASTPIN (-5275 3450) $PN D5
J 2
(-5285 3460);
DISPLAY 0.617021 (-5285 3460);
PAINT ORANGE (-5285 3460);
FORCEPROP 2 LASTPIN (-5275 3400) $PN D17
J 2
(-5285 3410);
DISPLAY 0.617021 (-5285 3410);
PAINT ORANGE (-5285 3410);
FORCEPROP 2 LASTPIN (-5275 3350) $PN D65
J 2
(-5285 3360);
DISPLAY 0.617021 (-5285 3360);
PAINT ORANGE (-5285 3360);
FORCEPROP 2 LASTPIN (-5275 3300) $PN D83
J 2
(-5285 3310);
DISPLAY 0.617021 (-5285 3310);
PAINT ORANGE (-5285 3310);
FORCEPROP 2 LASTPIN (-5275 3250) $PN E2
J 2
(-5285 3260);
DISPLAY 0.617021 (-5285 3260);
PAINT ORANGE (-5285 3260);
FORCEPROP 2 LASTPIN (-5275 3200) $PN E4
J 2
(-5285 3210);
DISPLAY 0.617021 (-5285 3210);
PAINT ORANGE (-5285 3210);
FORCEPROP 2 LASTPIN (-5275 3100) $PN E24
J 2
(-5285 3110);
DISPLAY 0.617021 (-5285 3110);
PAINT ORANGE (-5285 3110);
FORCEPROP 2 LASTPIN (-5275 3050) $PN E84
J 2
(-5285 3060);
DISPLAY 0.617021 (-5285 3060);
PAINT ORANGE (-5285 3060);
FORCEPROP 2 LASTPIN (-5275 3000) $PN F3
J 2
(-5285 3010);
DISPLAY 0.617021 (-5285 3010);
PAINT ORANGE (-5285 3010);
FORCEPROP 2 LASTPIN (-5275 2950) $PN F23
J 2
(-5285 2960);
DISPLAY 0.617021 (-5285 2960);
PAINT ORANGE (-5285 2960);
FORCEPROP 2 LASTPIN (-5275 2850) $PN F65
J 2
(-5285 2860);
DISPLAY 0.617021 (-5285 2860);
PAINT ORANGE (-5285 2860);
FORCEPROP 2 LASTPIN (-5275 2800) $PN F83
J 2
(-5285 2810);
DISPLAY 0.617021 (-5285 2810);
PAINT ORANGE (-5285 2810);
FORCEPROP 2 LASTPIN (-5275 2700) $PN G2
J 2
(-5285 2710);
DISPLAY 0.617021 (-5285 2710);
PAINT ORANGE (-5285 2710);
FORCEPROP 2 LASTPIN (-5275 2650) $PN G64
J 2
(-5285 2660);
DISPLAY 0.617021 (-5285 2660);
PAINT ORANGE (-5285 2660);
FORCEPROP 2 LASTPIN (-5275 2600) $PN G84
J 2
(-5285 2610);
DISPLAY 0.617021 (-5285 2610);
PAINT ORANGE (-5285 2610);
FORCEPROP 2 LASTPIN (-5275 2550) $PN H1
J 2
(-5285 2560);
DISPLAY 0.617021 (-5285 2560);
PAINT ORANGE (-5285 2560);
FORCEPROP 2 LASTPIN (-5275 2500) $PN H83
J 2
(-5285 2510);
DISPLAY 0.617021 (-5285 2510);
PAINT ORANGE (-5285 2510);
FORCEPROP 2 LASTPIN (-5275 2450) $PN H85
J 2
(-5285 2460);
DISPLAY 0.617021 (-5285 2460);
PAINT ORANGE (-5285 2460);
FORCEPROP 2 LASTPIN (-5275 2400) $PN J46
J 2
(-5285 2410);
DISPLAY 0.617021 (-5285 2410);
PAINT ORANGE (-5285 2410);
FORCEPROP 2 LASTPIN (-5275 2350) $PN J62
J 2
(-5285 2360);
DISPLAY 0.617021 (-5285 2360);
PAINT ORANGE (-5285 2360);
FORCEPROP 2 LASTPIN (-5275 2300) $PN K61
J 2
(-5285 2310);
DISPLAY 0.617021 (-5285 2310);
PAINT ORANGE (-5285 2310);
FORCEPROP 2 LASTPIN (-5275 2250) $PN M63
J 2
(-5285 2260);
DISPLAY 0.617021 (-5285 2260);
PAINT ORANGE (-5285 2260);
FORCEPROP 2 LASTPIN (-5275 2200) $PN P65
J 2
(-5285 2210);
DISPLAY 0.617021 (-5285 2210);
PAINT ORANGE (-5285 2210);
FORCEPROP 2 LASTPIN (-5275 2150) $PN R62
J 2
(-5285 2160);
DISPLAY 0.617021 (-5285 2160);
PAINT ORANGE (-5285 2160);
FORCEPROP 2 LASTPIN (-5275 2100) $PN R66
J 2
(-5285 2110);
DISPLAY 0.617021 (-5285 2110);
PAINT ORANGE (-5285 2110);
FORCEPROP 2 LASTPIN (-5275 2050) $PN T67
J 2
(-5285 2060);
DISPLAY 0.617021 (-5285 2060);
PAINT ORANGE (-5285 2060);
FORCEPROP 2 LASTPIN (-5275 2000) $PN U66
J 2
(-5285 2010);
DISPLAY 0.617021 (-5285 2010);
PAINT ORANGE (-5285 2010);
FORCEPROP 2 LASTPIN (-5275 1950) $PN V65
J 2
(-5285 1960);
DISPLAY 0.617021 (-5285 1960);
PAINT ORANGE (-5285 1960);
FORCEPROP 2 LASTPIN (-5275 1850) $PN V67
J 2
(-5285 1860);
DISPLAY 0.617021 (-5285 1860);
PAINT ORANGE (-5285 1860);
FORCEPROP 2 LASTPIN (-5275 1800) $PN W66
J 2
(-5285 1810);
DISPLAY 0.617021 (-5285 1810);
PAINT ORANGE (-5285 1810);
FORCEPROP 2 LASTPIN (-5275 1750) $PN Y23
J 2
(-5285 1760);
DISPLAY 0.617021 (-5285 1760);
PAINT ORANGE (-5285 1760);
FORCEPROP 2 LASTPIN (-5275 1700) $PN Y65
J 2
(-5285 1710);
DISPLAY 0.617021 (-5285 1710);
PAINT ORANGE (-5285 1710);
FORCEPROP 2 LASTPIN (-5275 1500) $PN AD47
J 2
(-5285 1510);
DISPLAY 0.617021 (-5285 1510);
PAINT ORANGE (-5285 1510);
FORCEPROP 2 LASTPIN (-5275 1450) $PN AD49
J 2
(-5285 1460);
DISPLAY 0.617021 (-5285 1460);
PAINT ORANGE (-5285 1460);
FORCEPROP 2 LASTPIN (-5275 1400) $PN AD51
J 2
(-5285 1410);
DISPLAY 0.617021 (-5285 1410);
PAINT ORANGE (-5285 1410);
FORCEPROP 2 LASTPIN (-5275 1350) $PN AE46
J 2
(-5285 1360);
DISPLAY 0.617021 (-5285 1360);
PAINT ORANGE (-5285 1360);
FORCEPROP 2 LASTPIN (-5275 1300) $PN AE48
J 2
(-5285 1310);
DISPLAY 0.617021 (-5285 1310);
PAINT ORANGE (-5285 1310);
FORCEPROP 2 LASTPIN (-5275 1250) $PN AE50
J 2
(-5285 1260);
DISPLAY 0.617021 (-5285 1260);
PAINT ORANGE (-5285 1260);
FORCEPROP 2 LASTPIN (-5275 1150) $PN AE52
J 2
(-5285 1160);
DISPLAY 0.617021 (-5285 1160);
PAINT ORANGE (-5285 1160);
FORCEPROP 2 LASTPIN (-5275 1100) $PN AE72
J 2
(-5285 1110);
DISPLAY 0.617021 (-5285 1110);
PAINT ORANGE (-5285 1110);
FORCEPROP 2 LASTPIN (-5275 1050) $PN AF19
J 2
(-5285 1060);
DISPLAY 0.617021 (-5285 1060);
PAINT ORANGE (-5285 1060);
FORCEPROP 2 LASTPIN (-5275 1000) $PN AF47
J 2
(-5285 1010);
DISPLAY 0.617021 (-5285 1010);
PAINT ORANGE (-5285 1010);
FORCEPROP 2 LASTPIN (-5275 950) $PN AF49
J 2
(-5285 960);
DISPLAY 0.617021 (-5285 960);
PAINT ORANGE (-5285 960);
FORCEPROP 2 LASTPIN (-5275 900) $PN AF51
J 2
(-5285 910);
DISPLAY 0.617021 (-5285 910);
PAINT ORANGE (-5285 910);
FORCEPROP 2 LASTPIN (-5275 750) $PN AF53
J 2
(-5285 760);
DISPLAY 0.617021 (-5285 760);
PAINT ORANGE (-5285 760);
FORCEPROP 2 LASTPIN (-2775 4350) $PN AF71
J 0
(-2765 4360);
DISPLAY 0.617021 (-2765 4360);
PAINT ORANGE (-2765 4360);
FORCEPROP 2 LASTPIN (-2775 4300) $PN AG20
J 0
(-2765 4310);
DISPLAY 0.617021 (-2765 4310);
PAINT ORANGE (-2765 4310);
FORCEPROP 2 LASTPIN (-2775 4250) $PN AG48
J 0
(-2765 4260);
DISPLAY 0.617021 (-2765 4260);
PAINT ORANGE (-2765 4260);
FORCEPROP 2 LASTPIN (-2775 4200) $PN AG50
J 0
(-2765 4210);
DISPLAY 0.617021 (-2765 4210);
PAINT ORANGE (-2765 4210);
FORCEPROP 2 LASTPIN (-2775 4150) $PN AG52
J 0
(-2765 4160);
DISPLAY 0.617021 (-2765 4160);
PAINT ORANGE (-2765 4160);
FORCEPROP 2 LASTPIN (-2775 4100) $PN AG54
J 0
(-2765 4110);
DISPLAY 0.617021 (-2765 4110);
PAINT ORANGE (-2765 4110);
FORCEPROP 2 LASTPIN (-2775 4050) $PN AG56
J 0
(-2765 4060);
DISPLAY 0.617021 (-2765 4060);
PAINT ORANGE (-2765 4060);
FORCEPROP 2 LASTPIN (-2775 3950) $PN AG72
J 0
(-2765 3960);
DISPLAY 0.617021 (-2765 3960);
PAINT ORANGE (-2765 3960);
FORCEPROP 2 LASTPIN (-2775 3900) $PN AH15
J 0
(-2765 3910);
DISPLAY 0.617021 (-2765 3910);
PAINT ORANGE (-2765 3910);
FORCEPROP 2 LASTPIN (-2775 3850) $PN AH19
J 0
(-2765 3860);
DISPLAY 0.617021 (-2765 3860);
PAINT ORANGE (-2765 3860);
FORCEPROP 2 LASTPIN (-2775 3800) $PN AH55
J 0
(-2765 3810);
DISPLAY 0.617021 (-2765 3810);
PAINT ORANGE (-2765 3810);
FORCEPROP 2 LASTPIN (-2775 3750) $PN AH57
J 0
(-2765 3760);
DISPLAY 0.617021 (-2765 3760);
PAINT ORANGE (-2765 3760);
FORCEPROP 2 LASTPIN (-2775 3700) $PN AH71
J 0
(-2765 3710);
DISPLAY 0.617021 (-2765 3710);
PAINT ORANGE (-2765 3710);
FORCEPROP 2 LASTPIN (-2775 3650) $PN AH73
J 0
(-2765 3660);
DISPLAY 0.617021 (-2765 3660);
PAINT ORANGE (-2765 3660);
FORCEPROP 2 LASTPIN (-2775 3550) $PN AJ20
J 0
(-2765 3560);
DISPLAY 0.617021 (-2765 3560);
PAINT ORANGE (-2765 3560);
FORCEPROP 2 LASTPIN (-2775 3500) $PN AJ56
J 0
(-2765 3510);
DISPLAY 0.617021 (-2765 3510);
PAINT ORANGE (-2765 3510);
FORCEPROP 2 LASTPIN (-2775 3450) $PN AJ58
J 0
(-2765 3460);
DISPLAY 0.617021 (-2765 3460);
PAINT ORANGE (-2765 3460);
FORCEPROP 2 LASTPIN (-2775 3400) $PN AJ60
J 0
(-2765 3410);
DISPLAY 0.617021 (-2765 3410);
PAINT ORANGE (-2765 3410);
FORCEPROP 2 LASTPIN (-2775 3350) $PN AJ62
J 0
(-2765 3360);
DISPLAY 0.617021 (-2765 3360);
PAINT ORANGE (-2765 3360);
FORCEPROP 2 LASTPIN (-2775 3300) $PN AJ70
J 0
(-2765 3310);
DISPLAY 0.617021 (-2765 3310);
PAINT ORANGE (-2765 3310);
FORCEPROP 2 LASTPIN (-2775 3250) $PN AK21
J 0
(-2765 3260);
DISPLAY 0.617021 (-2765 3260);
PAINT ORANGE (-2765 3260);
FORCEPROP 2 LASTPIN (-2775 2700) $PN AK27
J 0
(-2765 2710);
DISPLAY 0.617021 (-2765 2710);
PAINT ORANGE (-2765 2710);
FORCEPROP 2 LASTPIN (-2775 2600) $PN AK57
J 0
(-2765 2610);
DISPLAY 0.617021 (-2765 2610);
PAINT ORANGE (-2765 2610);
FORCEPROP 2 LASTPIN (-2775 2550) $PN AK59
J 0
(-2765 2560);
DISPLAY 0.617021 (-2765 2560);
PAINT ORANGE (-2765 2560);
FORCEPROP 2 LASTPIN (-2775 2500) $PN AK61
J 0
(-2765 2510);
DISPLAY 0.617021 (-2765 2510);
PAINT ORANGE (-2765 2510);
FORCEPROP 2 LASTPIN (-2775 2250) $PN AK69
J 0
(-2765 2260);
DISPLAY 0.617021 (-2765 2260);
PAINT ORANGE (-2765 2260);
FORCEPROP 2 LASTPIN (-2775 2200) $PN AL20
J 0
(-2765 2210);
DISPLAY 0.617021 (-2765 2210);
PAINT ORANGE (-2765 2210);
FORCEPROP 2 LASTPIN (-2775 2000) $PN AL22
J 0
(-2765 2010);
DISPLAY 0.617021 (-2765 2010);
PAINT ORANGE (-2765 2010);
FORCEPROP 2 LASTPIN (-2775 1850) $PN AL26
J 0
(-2765 1860);
DISPLAY 0.617021 (-2765 1860);
PAINT ORANGE (-2765 1860);
FORCEPROP 2 LASTPIN (-2775 1800) $PN AL58
J 0
(-2765 1810);
DISPLAY 0.617021 (-2765 1810);
PAINT ORANGE (-2765 1810);
FORCEPROP 2 LASTPIN (-2775 1750) $PN AL60
J 0
(-2765 1760);
DISPLAY 0.617021 (-2765 1760);
PAINT ORANGE (-2765 1760);
FORCEPROP 2 LASTPIN (-2775 1700) $PN AL62
J 0
(-2765 1710);
DISPLAY 0.617021 (-2765 1710);
PAINT ORANGE (-2765 1710);
FORCEPROP 2 LASTPIN (-2775 1650) $PN AM21
J 0
(-2765 1660);
DISPLAY 0.617021 (-2765 1660);
PAINT ORANGE (-2765 1660);
FORCEPROP 2 LASTPIN (-2775 1550) $PN AM23
J 0
(-2765 1560);
DISPLAY 0.617021 (-2765 1560);
PAINT ORANGE (-2765 1560);
FORCEPROP 2 LASTPIN (-2775 1500) $PN AM25
J 0
(-2765 1510);
DISPLAY 0.617021 (-2765 1510);
PAINT ORANGE (-2765 1510);
FORCEPROP 2 LASTPIN (-2775 1450) $PN AM27
J 0
(-2765 1460);
DISPLAY 0.617021 (-2765 1460);
PAINT ORANGE (-2765 1460);
FORCEPROP 2 LASTPIN (-2775 1400) $PN AM59
J 0
(-2765 1410);
DISPLAY 0.617021 (-2765 1410);
PAINT ORANGE (-2765 1410);
FORCEPROP 2 LASTPIN (-2775 1350) $PN AM61
J 0
(-2765 1360);
DISPLAY 0.617021 (-2765 1360);
PAINT ORANGE (-2765 1360);
FORCEPROP 2 LASTPIN (-2775 1300) $PN AN18
J 0
(-2765 1310);
DISPLAY 0.617021 (-2765 1310);
PAINT ORANGE (-2765 1310);
FORCEPROP 2 LASTPIN (-2775 1200) $PN AN22
J 0
(-2765 1210);
DISPLAY 0.617021 (-2765 1210);
PAINT ORANGE (-2765 1210);
FORCEPROP 2 LASTPIN (-2775 1150) $PN AN24
J 0
(-2765 1160);
DISPLAY 0.617021 (-2765 1160);
PAINT ORANGE (-2765 1160);
FORCEPROP 2 LASTPIN (-2775 1100) $PN AN26
J 0
(-2765 1110);
DISPLAY 0.617021 (-2765 1110);
PAINT ORANGE (-2765 1110);
FORCEPROP 2 LASTPIN (-2775 1050) $PN AN60
J 0
(-2765 1060);
DISPLAY 0.617021 (-2765 1060);
PAINT ORANGE (-2765 1060);
FORCEPROP 2 LASTPIN (-2775 1000) $PN AN62
J 0
(-2765 1010);
DISPLAY 0.617021 (-2765 1010);
PAINT ORANGE (-2765 1010);
FORCEPROP 2 LASTPIN (-2775 950) $PN AP23
J 0
(-2765 960);
DISPLAY 0.617021 (-2765 960);
PAINT ORANGE (-2765 960);
FORCEPROP 2 LASTPIN (-2775 900) $PN AP25
J 0
(-2765 910);
DISPLAY 0.617021 (-2765 910);
PAINT ORANGE (-2765 910);
FORCEPROP 2 LASTPIN (-2775 850) $PN AP27
J 0
(-2765 860);
DISPLAY 0.617021 (-2765 860);
PAINT ORANGE (-2765 860);
FORCEPROP 2 LASTPIN (-2775 800) $PN AP61
J 0
(-2765 810);
DISPLAY 0.617021 (-2765 810);
PAINT ORANGE (-2765 810);
FORCEPROP 2 LASTPIN (-2775 2850) $PN AP17
J 0
(-2765 2860);
DISPLAY 0.617021 (-2765 2860);
PAINT ORANGE (-2765 2860);
FORCEPROP 2 LASTPIN (-2775 2650) $PN AU14
J 0
(-2765 2660);
DISPLAY 0.617021 (-2765 2660);
PAINT ORANGE (-2765 2660);
FORCEPROP 2 LASTPIN (-2775 2050) $PN AW12
J 0
(-2765 2060);
DISPLAY 0.617021 (-2765 2060);
PAINT ORANGE (-2765 2060);
FORCEPROP 2 LASTPIN (-2775 2450) $PN AV21
J 0
(-2765 2460);
DISPLAY 0.617021 (-2765 2460);
PAINT ORANGE (-2765 2460);
FORCEPROP 1 LAST PACK_TYPE BGA1
J 0
(-5225 4650);
PAINT SKYBLUE (-5225 4650);
DISPLAY INVISIBLE (-5225 4650);
FORCEPROP 2 LAST CDS_LIB chpset_lib
J 0
(-4025 2550);
PAINT ORANGE (-4025 2550);
DISPLAY INVISIBLE (-4025 2550);
FORCEPROP 2 LAST SEC_TYPE BGA1
J 0
(-5225 4650);
DISPLAY 1.021277 (-5225 4650);
PAINT ORANGE (-5225 4650);
DISPLAY INVISIBLE (-5225 4650);
FORCEPROP 2 LAST SEC 2
J 0
(-5225 4650);
DISPLAY 0.680851 (-5225 4650);
PAINT MONO (-5225 4650);
DISPLAY INVISIBLE (-5225 4650);
FORCEPROP 2 LAST CDS_LOCATION U2D1
J 0
(-5225 4600);
DISPLAY 0.617021 (-5225 4600);
PAINT AQUA (-5225 4600);
DISPLAY INVISIBLE (-5225 4600);
FORCEPROP 1 LAST PATH I169
J 0
(-4025 4550);
PAINT GREEN (-4025 4550);
DISPLAY INVISIBLE (-4025 4550);
FORCEADD GND..1
(-275 2425);
FORCEPROP 3 LASTPIN (-275 2475) SIG_NAME GND\g
J 0
(-265 2485);
DISPLAY 0.659574 (-265 2485);
PAINT MONO (-265 2485);
DISPLAY INVISIBLE (-265 2485);
FORCEPROP 1 LAST VOLTAGE 0.0V
J 0
(-320 2382);
DISPLAY 0.340426 (-320 2382);
PAINT SKYBLUE (-320 2382);
DISPLAY INVISIBLE (-320 2382);
FORCEPROP 1 LAST SIZE 1B
J 0
(-200 2375);
DISPLAY 1.170213 (-200 2375);
PAINT GREEN (-200 2375);
DISPLAY INVISIBLE (-200 2375);
FORCEPROP 2 LAST CDS_LIB mstr_symbols
J 0
(-275 2425);
PAINT MONO (-275 2425);
DISPLAY INVISIBLE (-275 2425);
FORCEPROP 1 LAST BODY_TYPE PLUMBING
J 0
(-320 2382);
DISPLAY 0.340426 (-320 2382);
PAINT GREEN (-320 2382);
DISPLAY INVISIBLE (-320 2382);
FORCEPROP 1 LAST PATH I171
J 0
(-200 2425);
DISPLAY 0.872340 (-200 2425);
PAINT AQUA (-200 2425);
DISPLAY INVISIBLE (-200 2425);
FORCEPROP 1 LAST HDL_POWER GND
J 0
(-275 2575);
DISPLAY 0.702128 (-275 2575);
PAINT GREEN (-275 2575);
DISPLAY INVISIBLE (-275 2575);
FORCEADD RES..2
(-550 2750);
FORCEPROP 1 LAST LOCATION R8P3
J 0
(-505 2875);
DISPLAY 0.617021 (-505 2875);
PAINT AQUA (-505 2875);
FORCEPROP 1 LAST PART_NUMBER G21796-047
J 0
(-510 2625);
DISPLAY 0.617021 (-510 2625);
PAINT BLUE (-510 2625);
FORCEPROP 1 LAST VALUE 49.9
J 0
(-505 2825);
DISPLAY 0.617021 (-505 2825);
PAINT SKYBLUE (-505 2825);
FORCEPROP 1 LAST TOLERANCE 1%
J 0
(-505 2775);
DISPLAY 0.617021 (-505 2775);
PAINT SKYBLUE (-505 2775);
FORCEPROP 1 LAST PACK_TYPE 0402
J 0
(-510 2575);
DISPLAY 0.617021 (-510 2575);
PAINT SKYBLUE (-510 2575);
FORCEPROP 1 LAST MATERIAL CHIP
J 0
(-510 2675);
DISPLAY 0.617021 (-510 2675);
PAINT SKYBLUE (-510 2675);
FORCEPROP 1 LAST WATTAGE 1/16W
J 0
(-510 2725);
DISPLAY 0.617021 (-510 2725);
PAINT SKYBLUE (-510 2725);
FORCEPROP 1 LASTPIN (-550 2650) $PN 2
J 0
(-545 2660);
DISPLAY 0.617021 (-545 2660);
PAINT ORANGE (-545 2660);
FORCEPROP 1 LASTPIN (-550 2850) $PN 1
J 0
(-545 2812);
DISPLAY 0.617021 (-545 2812);
PAINT ORANGE (-545 2812);
FORCEPROP 2 LAST SEC_TYPE 0402
J 0
(-500 2975);
DISPLAY 1.021277 (-500 2975);
PAINT ORANGE (-500 2975);
DISPLAY INVISIBLE (-500 2975);
FORCEPROP 2 LAST CDS_LIB mstr_discrete
J 0
(-550 2750);
PAINT MONO (-550 2750);
DISPLAY INVISIBLE (-550 2750);
FORCEPROP 2 LAST SEC 1
J 0
(-500 2975);
DISPLAY 0.680851 (-500 2975);
PAINT MONO (-500 2975);
DISPLAY INVISIBLE (-500 2975);
FORCEPROP 2 LAST CDS_LOCATION R8P3
J 0
(-505 2875);
DISPLAY 0.617021 (-505 2875);
PAINT AQUA (-505 2875);
DISPLAY INVISIBLE (-505 2875);
FORCEPROP 1 LAST PATH I173
J 0
(-500 2925);
DISPLAY 0.978723 (-500 2925);
PAINT WHITE (-500 2925);
DISPLAY INVISIBLE (-500 2925);
FORCEPROP 0 LAST ROOM CPU1
J 0
(-500 2975);
DISPLAY 1.021277 (-500 2975);
PAINT ORANGE (-500 2975);
DISPLAY INVISIBLE (-500 2975);
FORCEADD RES..2
(-275 2750);
FORCEPROP 1 LAST LOCATION R8R1
J 0
(-230 2875);
DISPLAY 0.617021 (-230 2875);
PAINT AQUA (-230 2875);
FORCEPROP 1 LAST PART_NUMBER G21796-047
J 0
(-235 2625);
DISPLAY 0.617021 (-235 2625);
PAINT BLUE (-235 2625);
FORCEPROP 1 LAST VALUE 49.9
J 0
(-230 2825);
DISPLAY 0.617021 (-230 2825);
PAINT SKYBLUE (-230 2825);
FORCEPROP 1 LAST TOLERANCE 1%
J 0
(-230 2775);
DISPLAY 0.617021 (-230 2775);
PAINT SKYBLUE (-230 2775);
FORCEPROP 1 LAST PACK_TYPE 0402
J 0
(-235 2575);
DISPLAY 0.617021 (-235 2575);
PAINT SKYBLUE (-235 2575);
FORCEPROP 1 LAST MATERIAL CHIP
J 0
(-235 2675);
DISPLAY 0.617021 (-235 2675);
PAINT SKYBLUE (-235 2675);
FORCEPROP 1 LAST WATTAGE 1/16W
J 0
(-235 2725);
DISPLAY 0.617021 (-235 2725);
PAINT SKYBLUE (-235 2725);
FORCEPROP 1 LASTPIN (-275 2650) $PN 2
J 0
(-270 2660);
DISPLAY 0.617021 (-270 2660);
PAINT ORANGE (-270 2660);
FORCEPROP 1 LASTPIN (-275 2850) $PN 1
J 0
(-270 2812);
DISPLAY 0.617021 (-270 2812);
PAINT ORANGE (-270 2812);
FORCEPROP 2 LAST CDS_LIB mstr_discrete
J 0
(-275 2750);
PAINT MONO (-275 2750);
DISPLAY INVISIBLE (-275 2750);
FORCEPROP 2 LAST SEC_TYPE 0402
J 0
(-225 2975);
DISPLAY 1.021277 (-225 2975);
PAINT ORANGE (-225 2975);
DISPLAY INVISIBLE (-225 2975);
FORCEPROP 2 LAST SEC 1
J 0
(-225 2975);
DISPLAY 0.680851 (-225 2975);
PAINT MONO (-225 2975);
DISPLAY INVISIBLE (-225 2975);
FORCEPROP 2 LAST CDS_LOCATION R8R1
J 0
(-230 2875);
DISPLAY 0.617021 (-230 2875);
PAINT AQUA (-230 2875);
DISPLAY INVISIBLE (-230 2875);
FORCEPROP 1 LAST PATH I174
J 0
(-225 2925);
DISPLAY 0.978723 (-225 2925);
PAINT WHITE (-225 2925);
DISPLAY INVISIBLE (-225 2925);
FORCEPROP 0 LAST ROOM CPU1
J 0
(-225 2975);
DISPLAY 1.021277 (-225 2975);
PAINT ORANGE (-225 2975);
DISPLAY INVISIBLE (-225 2975);
FORCEADD OFFPAGE..4
(-1450 1450);
FORCEPROP 2 LAST $XR0 103 
J 0
(-1264 1450);
DISPLAY 0.638298 (-1264 1450);
PAINT MONO (-1264 1450);
FORCEPROP 2 LAST CDS_LIB mstr_standard
J 0
(-1450 1450);
PAINT MONO (-1450 1450);
DISPLAY INVISIBLE (-1450 1450);
FORCEPROP 1 LAST OFFPAGE TRUE
J 0
(-1125 1325);
DISPLAY 0.872340 (-1125 1325);
PAINT GREEN (-1125 1325);
DISPLAY INVISIBLE (-1125 1325);
FORCEPROP 1 LAST COMMENT_BODY TRUE
J 0
(-1475 1350);
DISPLAY 0.872340 (-1475 1350);
PAINT GREEN (-1475 1350);
DISPLAY INVISIBLE (-1475 1350);
FORCEPROP 2 LAST PATH I178
J 0
(-1275 1525);
DISPLAY 1.021277 (-1275 1525);
PAINT ORANGE (-1275 1525);
DISPLAY INVISIBLE (-1275 1525);
FORCEADD OFFPAGE..4
(-1450 850);
FORCEPROP 2 LAST $XR0 103 
J 0
(-1264 850);
DISPLAY 0.638298 (-1264 850);
PAINT MONO (-1264 850);
FORCEPROP 2 LAST CDS_LIB mstr_standard
J 0
(-1450 850);
PAINT MONO (-1450 850);
DISPLAY INVISIBLE (-1450 850);
FORCEPROP 1 LAST OFFPAGE TRUE
J 0
(-1125 725);
DISPLAY 0.872340 (-1125 725);
PAINT GREEN (-1125 725);
DISPLAY INVISIBLE (-1125 725);
FORCEPROP 1 LAST COMMENT_BODY TRUE
J 0
(-1475 750);
DISPLAY 0.872340 (-1475 750);
PAINT GREEN (-1475 750);
DISPLAY INVISIBLE (-1475 750);
FORCEPROP 2 LAST PATH I179
J 0
(-1275 925);
DISPLAY 1.021277 (-1275 925);
PAINT ORANGE (-1275 925);
DISPLAY INVISIBLE (-1275 925);
FORCEADD OFFPAGE..2
(-1450 1850);
FORCEPROP 2 LAST $XR0 104 
J 0
(-1261 1850);
DISPLAY 0.638298 (-1261 1850);
PAINT MONO (-1261 1850);
FORCEPROP 2 LAST CDS_LIB mstr_standard
J 0
(-1450 1850);
PAINT ORANGE (-1450 1850);
DISPLAY INVISIBLE (-1450 1850);
FORCEPROP 1 LAST OFFPAGE TRUE
J 0
(-1125 1725);
DISPLAY 0.489362 (-1125 1725);
PAINT GREEN (-1125 1725);
DISPLAY INVISIBLE (-1125 1725);
FORCEPROP 1 LAST COMMENT_BODY TRUE
J 0
(-1495 1755);
DISPLAY 0.936170 (-1495 1755);
PAINT PEACH (-1495 1755);
DISPLAY INVISIBLE (-1495 1755);
FORCEPROP 2 LAST PATH I180
J 0
(-1250 1900);
DISPLAY 1.021277 (-1250 1900);
PAINT ORANGE (-1250 1900);
DISPLAY INVISIBLE (-1250 1900);
FORCEADD OFFPAGE..4
(-1450 2050);
FORCEPROP 2 LAST $XR0 90 
J 0
(-1264 2050);
DISPLAY 0.638298 (-1264 2050);
PAINT MONO (-1264 2050);
FORCEPROP 2 LAST CDS_LIB mstr_standard
J 0
(-1450 2050);
DISPLAY 0.489362 (-1450 2050);
PAINT ORANGE (-1450 2050);
DISPLAY INVISIBLE (-1450 2050);
FORCEPROP 1 LAST OFFPAGE TRUE
J 0
(-1125 1925);
DISPLAY 0.680851 (-1125 1925);
PAINT GREEN (-1125 1925);
DISPLAY INVISIBLE (-1125 1925);
FORCEPROP 1 LAST COMMENT_BODY TRUE
J 0
(-1475 1950);
DISPLAY 0.680851 (-1475 1950);
PAINT PEACH (-1475 1950);
DISPLAY INVISIBLE (-1475 1950);
FORCEPROP 2 LAST PATH I181
J 0
(-1250 2100);
DISPLAY 1.021277 (-1250 2100);
PAINT ORANGE (-1250 2100);
DISPLAY INVISIBLE (-1250 2100);
FORCEADD OFFPAGE..4
(-1575 2700);
FORCEPROP 2 LAST $XR0 104 
J 0
(-1389 2700);
DISPLAY 0.638298 (-1389 2700);
PAINT MONO (-1389 2700);
FORCEPROP 2 LAST CDS_LIB mstr_standard
J 0
(-1575 2700);
PAINT ORANGE (-1575 2700);
DISPLAY INVISIBLE (-1575 2700);
FORCEPROP 1 LAST OFFPAGE TRUE
J 0
(-1250 2575);
DISPLAY 0.680851 (-1250 2575);
PAINT GREEN (-1250 2575);
DISPLAY INVISIBLE (-1250 2575);
FORCEPROP 1 LAST COMMENT_BODY TRUE
J 0
(-1600 2600);
DISPLAY 0.680851 (-1600 2600);
PAINT PEACH (-1600 2600);
DISPLAY INVISIBLE (-1600 2600);
FORCEPROP 2 LAST PATH I182
J 0
(-1375 2750);
DISPLAY 1.021277 (-1375 2750);
PAINT ORANGE (-1375 2750);
DISPLAY INVISIBLE (-1375 2750);
FORCEADD OFFPAGE..2
(-1550 2650);
FORCEPROP 2 LAST $XR0 92 
J 0
(-1361 2650);
DISPLAY 0.638298 (-1361 2650);
PAINT MONO (-1361 2650);
FORCEPROP 2 LAST CDS_LIB mstr_standard
J 0
(-1550 2650);
DISPLAY 0.787234 (-1550 2650);
PAINT MONO (-1550 2650);
DISPLAY INVISIBLE (-1550 2650);
FORCEPROP 1 LAST OFFPAGE TRUE
J 0
(-1225 2525);
DISPLAY 0.489362 (-1225 2525);
PAINT GREEN (-1225 2525);
DISPLAY INVISIBLE (-1225 2525);
FORCEPROP 1 LAST COMMENT_BODY TRUE
J 0
(-1595 2555);
DISPLAY 0.936170 (-1595 2555);
PAINT PEACH (-1595 2555);
DISPLAY INVISIBLE (-1595 2555);
FORCEPROP 2 LAST PATH I183
J 0
(-1350 2700);
DISPLAY 1.021277 (-1350 2700);
PAINT ORANGE (-1350 2700);
DISPLAY INVISIBLE (-1350 2700);
FORCEADD VCC_CORE..1
(-950 2325);
FORCEPROP 3 LASTPIN (-950 2275) SIG_NAME PVCCMCP_CPU1\g
J 0
(-940 2285);
DISPLAY 0.659574 (-940 2285);
PAINT MONO (-940 2285);
DISPLAY INVISIBLE (-940 2285);
FORCEPROP 1 LAST HDL_POWER PVCCMCP_CPU1
J 1
(-950 2375);
DISPLAY 0.617021 (-950 2375);
PAINT GREEN (-950 2375);
FORCEPROP 2 LAST CDS_LIB mstr_symbols
J 0
(-950 2325);
PAINT ORANGE (-950 2325);
DISPLAY INVISIBLE (-950 2325);
FORCEPROP 1 LAST PATH I185
J 0
(-900 2350);
DISPLAY 0.872340 (-900 2350);
PAINT AQUA (-900 2350);
DISPLAY INVISIBLE (-900 2350);
FORCEADD OFFPAGE..2
R 2
(-7100 1750);
FORCEPROP 2 LAST $XR0 133 
J 0
(-7355 1750);
DISPLAY 0.638298 (-7355 1750);
PAINT MONO (-7355 1750);
FORCEPROP 2 LAST $XR1 120 
J 0
(-7475 1750);
DISPLAY 0.638298 (-7475 1750);
PAINT MONO (-7475 1750);
FORCEPROP 2 LAST $XR2 145 
J 0
(-7595 1750);
DISPLAY 0.638298 (-7595 1750);
PAINT MONO (-7595 1750);
FORCEPROP 2 LAST CDS_LIB mstr_standard
J 2
(-7100 1750);
PAINT ORANGE (-7100 1750);
DISPLAY INVISIBLE (-7100 1750);
FORCEPROP 1 LAST OFFPAGE TRUE
J 2
(-7425 1625);
DISPLAY 0.489362 (-7425 1625);
PAINT GREEN (-7425 1625);
DISPLAY INVISIBLE (-7425 1625);
FORCEPROP 1 LAST COMMENT_BODY TRUE
J 2
(-7055 1655);
DISPLAY 0.936170 (-7055 1655);
PAINT PEACH (-7055 1655);
DISPLAY INVISIBLE (-7055 1655);
FORCEPROP 2 LAST PATH I187
J 2
(-7275 1825);
DISPLAY 1.021277 (-7275 1825);
PAINT ORANGE (-7275 1825);
DISPLAY INVISIBLE (-7275 1825);
FORCEADD VCC_CORE..1
(-7250 4350);
FORCEPROP 3 LASTPIN (-7250 4300) SIG_NAME P1V8_MCP_CPU1\g
J 0
(-7240 4310);
DISPLAY 0.659574 (-7240 4310);
PAINT MONO (-7240 4310);
DISPLAY INVISIBLE (-7240 4310);
FORCEPROP 1 LAST HDL_POWER P1V8_MCP_CPU1
J 1
(-7250 4400);
DISPLAY 0.617021 (-7250 4400);
PAINT GREEN (-7250 4400);
FORCEPROP 0 LAST VOLTAGE 1.8
J 0
(-7250 4500);
DISPLAY 1.021277 (-7250 4500);
PAINT SKYBLUE (-7250 4500);
DISPLAY INVISIBLE (-7250 4500);
FORCEPROP 2 LAST CDS_LIB mstr_symbols
J 0
(-7250 4350);
PAINT ORANGE (-7250 4350);
DISPLAY INVISIBLE (-7250 4350);
FORCEPROP 1 LAST PATH I188
J 0
(-7200 4375);
DISPLAY 0.872340 (-7200 4375);
PAINT AQUA (-7200 4375);
DISPLAY INVISIBLE (-7200 4375);
FORCEADD OFFPAGE..4
(-1450 3250);
FORCEPROP 2 LAST $XR0 193 
J 0
(-1264 3250);
DISPLAY 0.638298 (-1264 3250);
PAINT MONO (-1264 3250);
FORCEPROP 2 LAST CDS_LIB mstr_standard
J 0
(-1450 3250);
PAINT ORANGE (-1450 3250);
DISPLAY INVISIBLE (-1450 3250);
FORCEPROP 1 LAST OFFPAGE TRUE
J 0
(-1125 3125);
DISPLAY 0.680851 (-1125 3125);
PAINT GREEN (-1125 3125);
DISPLAY INVISIBLE (-1125 3125);
FORCEPROP 1 LAST COMMENT_BODY TRUE
J 0
(-1475 3150);
DISPLAY 0.680851 (-1475 3150);
PAINT PEACH (-1475 3150);
DISPLAY INVISIBLE (-1475 3150);
FORCEPROP 2 LAST PATH I189
J 0
(-1275 3325);
DISPLAY 1.021277 (-1275 3325);
PAINT ORANGE (-1275 3325);
DISPLAY INVISIBLE (-1275 3325);
FORCEADD OFFPAGE..4
(-1525 2200);
FORCEPROP 2 LAST $XR0 193 
J 0
(-1339 2200);
DISPLAY 0.638298 (-1339 2200);
PAINT MONO (-1339 2200);
FORCEPROP 2 LAST CDS_LIB mstr_standard
J 0
(-1525 2200);
PAINT ORANGE (-1525 2200);
DISPLAY INVISIBLE (-1525 2200);
FORCEPROP 1 LAST OFFPAGE TRUE
J 0
(-1200 2075);
DISPLAY 0.680851 (-1200 2075);
PAINT GREEN (-1200 2075);
DISPLAY INVISIBLE (-1200 2075);
FORCEPROP 1 LAST COMMENT_BODY TRUE
J 0
(-1550 2100);
DISPLAY 0.680851 (-1550 2100);
PAINT PEACH (-1550 2100);
DISPLAY INVISIBLE (-1550 2100);
FORCEPROP 2 LAST PATH I190
J 0
(-1350 2275);
DISPLAY 1.021277 (-1350 2275);
PAINT ORANGE (-1350 2275);
DISPLAY INVISIBLE (-1350 2275);
FORCEADD DESIGN_NOTE..1
(-5025 450);
FORCEPROP 0 LAST L1 CPU SYMBOLS 1-30 ARE PRELIMINARY AND SUBJECT TO CHANGE
J 0
(-5225 325);
DISPLAY 1.021277 (-5225 325);
PAINT ORANGE (-5225 325);
FORCEPROP 2 LAST CDS_LIB mstr_symbols
J 0
(-5025 450);
PAINT ORANGE (-5025 450);
DISPLAY INVISIBLE (-5025 450);
FORCEPROP 1 LAST COMMENT_BODY TRUE
J 0
(-5000 550);
DISPLAY 0.978723 (-5000 550);
PAINT ORANGE (-5000 550);
DISPLAY INVISIBLE (-5000 550);
FORCEADD DESIGN_NOTE..1
(-600 1725);
FORCEPROP 0 LAST L1 CLKS USED FOR DEBUG ONLY
J 0
(-775 1600);
DISPLAY 0.808511 (-775 1600);
PAINT ORANGE (-775 1600);
FORCEPROP 2 LAST CDS_LIB mstr_symbols
J 0
(-600 1725);
PAINT ORANGE (-600 1725);
DISPLAY INVISIBLE (-600 1725);
FORCEPROP 1 LAST COMMENT_BODY TRUE
J 0
(-575 1825);
DISPLAY 0.978723 (-575 1825);
PAINT ORANGE (-575 1825);
DISPLAY INVISIBLE (-575 1825);
FORCEADD INTEL_CORP_BPAGE..1
(0 0);
FORCEPROP 1 LAST CDS_CON_LAST_MODIFIED Tue Dec 01 11:51:33 2015
J 0
(-1425 325);
DISPLAY 1.340426 (-1425 325);
PAINT GREEN (-1425 325);
DISPLAY INVISIBLE (-1425 325);
FORCEPROP 1 LAST CUSTOM_TXT_CDS <CURRENT_DESIGN_SHEET> OF <TOTAL_DESIGN_SHEETS>
J 0
(-500 25);
PAINT GREEN (-500 25);
FORCEPROP 1 LAST CUSTOM_TXT_CDS <CON_LAST_MODIFIED>
J 0
(-1925 350);
PAINT GREEN (-1925 350);
FORCEPROP 2 LAST CUSTOM_TXT_CDS <XR_PAGE_TITLE>
J 0
(-7890 5250);
DISPLAY 0.638298 (-7890 5250);
PAINT PINK (-7890 5250);
DISPLAY INVISIBLE (-7890 5250);
FORCEPROP 1 LAST SCH_ADDRESS3 Santa Clara, CA 95052-8119
J 0
(-3975 25);
DISPLAY 0.617021 (-3975 25);
PAINT GREEN (-3975 25);
FORCEPROP 1 LAST SCH_ADDRESS2 P.O. BOX 58119
J 0
(-3975 75);
DISPLAY 0.617021 (-3975 75);
PAINT GREEN (-3975 75);
FORCEPROP 1 LAST SCH_ADDRESS1 2200 Mission College Blvd.
J 0
(-3975 125);
DISPLAY 0.617021 (-3975 125);
PAINT GREEN (-3975 125);
FORCEPROP 1 LAST SCH_TITLE SKYLAKE - SKT1 - 2 OF 21
J 0
(-7950 50);
DISPLAY 1.212766 (-7950 50);
PAINT GREEN (-7950 50);
FORCEPROP 1 LAST SCH_NUMBER H4694802
J 0
(-1300 150);
DISPLAY 1.212766 (-1300 150);
PAINT YELLOW (-1300 150);
FORCEPROP 1 LAST SCH_DEPT BESD
J 1
(-4450 100);
DISPLAY 1.212766 (-4450 100);
PAINT YELLOW (-4450 100);
FORCEPROP 1 LAST SCH_REV 2.420
J 0
(-250 150);
DISPLAY 0.978723 (-250 150);
PAINT YELLOW (-250 150);
FORCEPROP 2 LAST PAGE_BORDER TRUE
J 0
(-7890 5250);
DISPLAY 0.851064 (-7890 5250);
PAINT PINK (-7890 5250);
DISPLAY INVISIBLE (-7890 5250);
FORCEPROP 2 LAST CDS_LIB mstr_symbols
J 0
(0 0);
PAINT ORANGE (0 0);
DISPLAY INVISIBLE (0 0);
FORCEPROP 1 LAST COMMENT_BODY TRUE
J 0
(12 12);
DISPLAY 0.638298 (12 12);
PAINT GREEN (12 12);
DISPLAY INVISIBLE (12 12);
FORCEPROP 2 LAST CDS_XR_PAGE_TITLE CR-56 : @BASEBOARD_FAB2_LIB.BASEBOARD_FAB2(SCH_1):PAGE56
J 0
(-7890 5250);
DISPLAY 0.638298 (-7890 5250);
PAINT PINK (-7890 5250);
DISPLAY INVISIBLE (-7890 5250);
FORCEADD PRELIM..10
(-4240 2590);
PAINT GRAY (-4240 2590);
FORCEPROP 2 LAST CDS_LIB mstr_misc
J 0
(-4240 2590);
PAINT ORANGE (-4240 2590);
DISPLAY INVISIBLE (-4240 2590);
FORCEPROP 1 LAST COMMENT_BODY TRUE
J 0
(-4240 2590);
PAINT ORANGE (-4240 2590);
DISPLAY INVISIBLE (-4240 2590);
WIRE 16 -1 (-550 2650)(-550 2525);
WIRE 16 -1 (-550 2525)(-275 2525);
WIRE 16 -1 (-275 2650)(-275 2525);
WIRE 16 -1 (-275 2525)(-275 2475);
WIRE 16 -1 (-2775 1300)(-2550 1300);
WIRE 16 -1 (-2550 1300)(-2550 1200);
WIRE 16 -1 (-2775 1200)(-2550 1200);
WIRE 16 -1 (-2550 1200)(-2550 1150);
WIRE 16 -1 (-2775 1150)(-2550 1150);
WIRE 16 -1 (-2550 1150)(-2550 1100);
WIRE 16 -1 (-2775 1100)(-2550 1100);
WIRE 16 -1 (-2550 1100)(-950 1100);
WIRE 16 -1 (-950 900)(-950 1100);
WIRE 16 -1 (-950 1100)(-950 1500);
WIRE 16 -1 (-2775 1500)(-950 1500);
WIRE 16 -1 (-950 1500)(-950 1650);
WIRE 16 -1 (-2575 900)(-950 900);
WIRE 16 -1 (-2575 950)(-2575 900);
WIRE 16 -1 (-2775 900)(-2575 900);
WIRE 16 -1 (-2775 1650)(-950 1650);
WIRE 16 -1 (-950 1650)(-950 2275);
WIRE 16 -1 (-2775 950)(-2575 950);
WIRE 16 -1 (-5275 3850)(-5450 3850);
WIRE 16 -1 (-5450 3850)(-5450 3900);
WIRE 16 -1 (-5275 3900)(-5450 3900);
WIRE 16 -1 (-5450 3900)(-5450 3950);
WIRE 16 -1 (-5275 3950)(-5450 3950);
WIRE 16 -1 (-5450 3950)(-7250 3950);
WIRE 16 -1 (-7250 3950)(-7250 4250);
WIRE 16 -1 (-7250 4250)(-5450 4250);
WIRE 16 -1 (-7250 4300)(-7250 4250);
WIRE 16 -1 (-5450 4200)(-5450 4250);
WIRE 16 -1 (-5450 4250)(-5275 4250);
WIRE 16 -1 (-5275 4200)(-5450 4200);
WIRE 16 -1 (-5275 4350)(-6325 4350);
FORCEPROP 2 LAST SIG_NAME TP_CPU1_RSVD_304
J 0
(-6325 4360);
DISPLAY 0.617021 (-6325 4360);
PAINT ORANGE (-6325 4360);
FORCEPROP 2 LASTPROP $XRERR UNIQUE?
J 0
(-6565 4350);
DISPLAY 0.638298 (-6565 4350);
PAINT MONO (-6565 4350);
DISPLAY INVISIBLE (-6565 4350);
WIRE 16 -1 (-5275 3450)(-6325 3450);
FORCEPROP 2 LAST SIG_NAME TP_CPU1_RSVD_287
J 0
(-6300 3460);
DISPLAY 0.617021 (-6300 3460);
PAINT ORANGE (-6300 3460);
FORCEPROP 2 LASTPROP $XRERR UNIQUE?
J 0
(-6565 3450);
DISPLAY 0.638298 (-6565 3450);
PAINT MONO (-6565 3450);
DISPLAY INVISIBLE (-6565 3450);
WIRE 16 -1 (-5275 3400)(-6325 3400);
FORCEPROP 2 LAST SIG_NAME TP_CPU1_RSVD_286
J 0
(-6300 3410);
DISPLAY 0.617021 (-6300 3410);
PAINT ORANGE (-6300 3410);
FORCEPROP 2 LASTPROP $XRERR UNIQUE?
J 0
(-6565 3400);
DISPLAY 0.638298 (-6565 3400);
PAINT MONO (-6565 3400);
DISPLAY INVISIBLE (-6565 3400);
WIRE 16 -1 (-5275 2650)(-6325 2650);
FORCEPROP 2 LAST SIG_NAME TP_CPU1_RSVD_274
J 0
(-6300 2660);
DISPLAY 0.617021 (-6300 2660);
PAINT ORANGE (-6300 2660);
FORCEPROP 2 LASTPROP $XRERR UNIQUE?
J 0
(-6565 2650);
DISPLAY 0.638298 (-6565 2650);
PAINT MONO (-6565 2650);
DISPLAY INVISIBLE (-6565 2650);
WIRE 16 -1 (-5275 2350)(-6325 2350);
FORCEPROP 2 LAST SIG_NAME TP_CPU1_RSVD_268
J 0
(-6300 2360);
DISPLAY 0.617021 (-6300 2360);
PAINT ORANGE (-6300 2360);
FORCEPROP 2 LASTPROP $XRERR UNIQUE?
J 0
(-6565 2350);
DISPLAY 0.638298 (-6565 2350);
PAINT MONO (-6565 2350);
DISPLAY INVISIBLE (-6565 2350);
WIRE 16 -1 (-5275 2150)(-6325 2150);
FORCEPROP 2 LAST SIG_NAME TP_CPU1_RSVD_264
J 0
(-6300 2160);
DISPLAY 0.617021 (-6300 2160);
PAINT ORANGE (-6300 2160);
FORCEPROP 2 LASTPROP $XRERR UNIQUE?
J 0
(-6565 2150);
DISPLAY 0.638298 (-6565 2150);
PAINT MONO (-6565 2150);
DISPLAY INVISIBLE (-6565 2150);
WIRE 16 -1 (-5275 2100)(-6325 2100);
FORCEPROP 2 LAST SIG_NAME TP_CPU1_RSVD_263
J 0
(-6300 2110);
DISPLAY 0.617021 (-6300 2110);
PAINT ORANGE (-6300 2110);
FORCEPROP 2 LASTPROP $XRERR UNIQUE?
J 0
(-6565 2100);
DISPLAY 0.638298 (-6565 2100);
PAINT MONO (-6565 2100);
DISPLAY INVISIBLE (-6565 2100);
WIRE 16 -1 (-5275 1350)(-6325 1350);
FORCEPROP 2 LAST SIG_NAME TP_CPU1_RSVD_251
J 0
(-6300 1360);
DISPLAY 0.617021 (-6300 1360);
PAINT ORANGE (-6300 1360);
FORCEPROP 2 LASTPROP $XRERR UNIQUE?
J 0
(-6565 1350);
DISPLAY 0.638298 (-6565 1350);
PAINT MONO (-6565 1350);
DISPLAY INVISIBLE (-6565 1350);
WIRE 16 -1 (-6325 1300)(-5275 1300);
FORCEPROP 2 LAST SIG_NAME TP_CPU1_RSVD_250
J 0
(-6300 1310);
DISPLAY 0.617021 (-6300 1310);
PAINT ORANGE (-6300 1310);
FORCEPROP 2 LASTPROP $XRERR UNIQUE?
J 0
(-6565 1300);
DISPLAY 0.638298 (-6565 1300);
PAINT MONO (-6565 1300);
DISPLAY INVISIBLE (-6565 1300);
WIRE 16 -1 (-5275 1250)(-6325 1250);
FORCEPROP 2 LAST SIG_NAME TP_CPU1_RSVD_249
J 0
(-6300 1260);
DISPLAY 0.617021 (-6300 1260);
PAINT ORANGE (-6300 1260);
FORCEPROP 2 LASTPROP $XRERR UNIQUE?
J 0
(-6565 1250);
DISPLAY 0.638298 (-6565 1250);
PAINT MONO (-6565 1250);
DISPLAY INVISIBLE (-6565 1250);
WIRE 16 -1 (-5275 1150)(-6325 1150);
FORCEPROP 2 LAST SIG_NAME TP_CPU1_RSVD_248
J 0
(-6300 1160);
DISPLAY 0.617021 (-6300 1160);
PAINT ORANGE (-6300 1160);
FORCEPROP 2 LASTPROP $XRERR UNIQUE?
J 0
(-6565 1150);
DISPLAY 0.638298 (-6565 1150);
PAINT MONO (-6565 1150);
DISPLAY INVISIBLE (-6565 1150);
WIRE 16 -1 (-5275 1100)(-6325 1100);
FORCEPROP 2 LAST SIG_NAME TP_CPU1_RSVD_247
J 0
(-6300 1110);
DISPLAY 0.617021 (-6300 1110);
PAINT ORANGE (-6300 1110);
FORCEPROP 2 LASTPROP $XRERR UNIQUE?
J 0
(-6565 1100);
DISPLAY 0.638298 (-6565 1100);
PAINT MONO (-6565 1100);
DISPLAY INVISIBLE (-6565 1100);
WIRE 16 -1 (-5275 1050)(-6325 1050);
FORCEPROP 2 LAST SIG_NAME TP_CPU1_RSVD_246
J 0
(-6300 1060);
DISPLAY 0.617021 (-6300 1060);
PAINT ORANGE (-6300 1060);
FORCEPROP 2 LASTPROP $XRERR UNIQUE?
J 0
(-6565 1050);
DISPLAY 0.638298 (-6565 1050);
PAINT MONO (-6565 1050);
DISPLAY INVISIBLE (-6565 1050);
WIRE 16 -1 (-5275 1000)(-6325 1000);
FORCEPROP 2 LAST SIG_NAME TP_CPU1_RSVD_245
J 0
(-6300 1010);
DISPLAY 0.617021 (-6300 1010);
PAINT ORANGE (-6300 1010);
FORCEPROP 2 LASTPROP $XRERR UNIQUE?
J 0
(-6565 1000);
DISPLAY 0.638298 (-6565 1000);
PAINT MONO (-6565 1000);
DISPLAY INVISIBLE (-6565 1000);
WIRE 16 -1 (-5275 950)(-6325 950);
FORCEPROP 2 LAST SIG_NAME TP_CPU1_RSVD_244
J 0
(-6300 960);
DISPLAY 0.617021 (-6300 960);
PAINT ORANGE (-6300 960);
FORCEPROP 2 LASTPROP $XRERR UNIQUE?
J 0
(-6565 950);
DISPLAY 0.638298 (-6565 950);
PAINT MONO (-6565 950);
DISPLAY INVISIBLE (-6565 950);
WIRE 16 -1 (-5275 3500)(-6325 3500);
FORCEPROP 2 LAST SIG_NAME TP_CPU1_RSVD_288
J 0
(-6300 3510);
DISPLAY 0.617021 (-6300 3510);
PAINT ORANGE (-6300 3510);
FORCEPROP 2 LASTPROP $XRERR UNIQUE?
J 0
(-6565 3500);
DISPLAY 0.638298 (-6565 3500);
PAINT MONO (-6565 3500);
DISPLAY INVISIBLE (-6565 3500);
WIRE 16 -1 (-6325 3250)(-5275 3250);
FORCEPROP 2 LAST SIG_NAME TP_CPU1_RSVD_283
J 0
(-6300 3260);
DISPLAY 0.617021 (-6300 3260);
PAINT ORANGE (-6300 3260);
FORCEPROP 2 LASTPROP $XRERR UNIQUE?
J 0
(-6565 3250);
DISPLAY 0.638298 (-6565 3250);
PAINT MONO (-6565 3250);
DISPLAY INVISIBLE (-6565 3250);
WIRE 16 -1 (-6325 3200)(-5275 3200);
FORCEPROP 2 LAST SIG_NAME TP_CPU1_RSVD_282
J 0
(-6300 3210);
DISPLAY 0.617021 (-6300 3210);
PAINT ORANGE (-6300 3210);
FORCEPROP 2 LASTPROP $XRERR UNIQUE?
J 0
(-6565 3200);
DISPLAY 0.638298 (-6565 3200);
PAINT MONO (-6565 3200);
DISPLAY INVISIBLE (-6565 3200);
WIRE 16 -1 (-5275 3350)(-6325 3350);
FORCEPROP 2 LAST SIG_NAME TP_CPU1_RSVD_285
J 0
(-6300 3360);
DISPLAY 0.617021 (-6300 3360);
PAINT ORANGE (-6300 3360);
FORCEPROP 2 LASTPROP $XRERR UNIQUE?
J 0
(-6565 3350);
DISPLAY 0.638298 (-6565 3350);
PAINT MONO (-6565 3350);
DISPLAY INVISIBLE (-6565 3350);
WIRE 16 -1 (-5275 1400)(-6325 1400);
FORCEPROP 2 LAST SIG_NAME TP_CPU1_RSVD_252
J 0
(-6300 1410);
DISPLAY 0.617021 (-6300 1410);
PAINT ORANGE (-6300 1410);
FORCEPROP 2 LASTPROP $XRERR UNIQUE?
J 0
(-6565 1400);
DISPLAY 0.638298 (-6565 1400);
PAINT MONO (-6565 1400);
DISPLAY INVISIBLE (-6565 1400);
WIRE 16 -1 (-5275 2600)(-6325 2600);
FORCEPROP 2 LAST SIG_NAME TP_CPU1_RSVD_273
J 0
(-6300 2610);
DISPLAY 0.617021 (-6300 2610);
PAINT ORANGE (-6300 2610);
FORCEPROP 2 LASTPROP $XRERR UNIQUE?
J 0
(-6565 2600);
DISPLAY 0.638298 (-6565 2600);
PAINT MONO (-6565 2600);
DISPLAY INVISIBLE (-6565 2600);
WIRE 16 -1 (-5275 2550)(-6325 2550);
FORCEPROP 2 LAST SIG_NAME TP_CPU1_RSVD_272
J 0
(-6300 2560);
DISPLAY 0.617021 (-6300 2560);
PAINT ORANGE (-6300 2560);
FORCEPROP 2 LASTPROP $XRERR UNIQUE?
J 0
(-6565 2550);
DISPLAY 0.638298 (-6565 2550);
PAINT MONO (-6565 2550);
DISPLAY INVISIBLE (-6565 2550);
WIRE 16 -1 (-5275 2500)(-6325 2500);
FORCEPROP 2 LAST SIG_NAME TP_CPU1_RSVD_271
J 0
(-6300 2510);
DISPLAY 0.617021 (-6300 2510);
PAINT ORANGE (-6300 2510);
FORCEPROP 2 LASTPROP $XRERR UNIQUE?
J 0
(-6565 2500);
DISPLAY 0.638298 (-6565 2500);
PAINT MONO (-6565 2500);
DISPLAY INVISIBLE (-6565 2500);
WIRE 16 -1 (-5275 2400)(-6325 2400);
FORCEPROP 2 LAST SIG_NAME TP_CPU1_RSVD_269
J 0
(-6300 2410);
DISPLAY 0.617021 (-6300 2410);
PAINT ORANGE (-6300 2410);
FORCEPROP 2 LASTPROP $XRERR UNIQUE?
J 0
(-6565 2400);
DISPLAY 0.638298 (-6565 2400);
PAINT MONO (-6565 2400);
DISPLAY INVISIBLE (-6565 2400);
WIRE 16 -1 (-5275 4050)(-6325 4050);
FORCEPROP 2 LAST SIG_NAME TP_CPU1_RSVD_298
J 0
(-6300 4060);
DISPLAY 0.617021 (-6300 4060);
PAINT ORANGE (-6300 4060);
FORCEPROP 2 LASTPROP $XRERR UNIQUE?
J 0
(-6565 4050);
DISPLAY 0.638298 (-6565 4050);
PAINT MONO (-6565 4050);
DISPLAY INVISIBLE (-6565 4050);
WIRE 16 -1 (-5275 750)(-6325 750);
FORCEPROP 2 LAST SIG_NAME TP_CPU1_RSVD_242
J 0
(-6300 760);
DISPLAY 0.617021 (-6300 760);
PAINT ORANGE (-6300 760);
FORCEPROP 2 LASTPROP $XRERR UNIQUE?
J 0
(-6565 750);
DISPLAY 0.638298 (-6565 750);
PAINT MONO (-6565 750);
DISPLAY INVISIBLE (-6565 750);
WIRE 16 -1 (-5275 900)(-6325 900);
FORCEPROP 2 LAST SIG_NAME TP_CPU1_RSVD_243
J 0
(-6300 910);
DISPLAY 0.617021 (-6300 910);
PAINT ORANGE (-6300 910);
FORCEPROP 2 LASTPROP $XRERR UNIQUE?
J 0
(-6565 900);
DISPLAY 0.638298 (-6565 900);
PAINT MONO (-6565 900);
DISPLAY INVISIBLE (-6565 900);
WIRE 16 -1 (-5275 1950)(-6325 1950);
FORCEPROP 2 LAST SIG_NAME TP_CPU1_RSVD_260
J 0
(-6300 1960);
DISPLAY 0.617021 (-6300 1960);
PAINT ORANGE (-6300 1960);
FORCEPROP 2 LASTPROP $XRERR UNIQUE?
J 0
(-6565 1950);
DISPLAY 0.638298 (-6565 1950);
PAINT MONO (-6565 1950);
DISPLAY INVISIBLE (-6565 1950);
WIRE 16 -1 (-5275 2000)(-6325 2000);
FORCEPROP 2 LAST SIG_NAME TP_CPU1_RSVD_261
J 0
(-6300 2010);
DISPLAY 0.617021 (-6300 2010);
PAINT ORANGE (-6300 2010);
FORCEPROP 2 LASTPROP $XRERR UNIQUE?
J 0
(-6565 2000);
DISPLAY 0.638298 (-6565 2000);
PAINT MONO (-6565 2000);
DISPLAY INVISIBLE (-6565 2000);
WIRE 16 -1 (-5275 2050)(-6325 2050);
FORCEPROP 2 LAST SIG_NAME TP_CPU1_RSVD_262
J 0
(-6300 2060);
DISPLAY 0.617021 (-6300 2060);
PAINT ORANGE (-6300 2060);
FORCEPROP 2 LASTPROP $XRERR UNIQUE?
J 0
(-6565 2050);
DISPLAY 0.638298 (-6565 2050);
PAINT MONO (-6565 2050);
DISPLAY INVISIBLE (-6565 2050);
WIRE 16 -1 (-5275 2250)(-6325 2250);
FORCEPROP 2 LAST SIG_NAME TP_CPU1_RSVD_266
J 0
(-6300 2260);
DISPLAY 0.617021 (-6300 2260);
PAINT ORANGE (-6300 2260);
FORCEPROP 2 LASTPROP $XRERR UNIQUE?
J 0
(-6565 2250);
DISPLAY 0.638298 (-6565 2250);
PAINT MONO (-6565 2250);
DISPLAY INVISIBLE (-6565 2250);
WIRE 16 -1 (-5275 2300)(-6325 2300);
FORCEPROP 2 LAST SIG_NAME TP_CPU1_RSVD_267
J 0
(-6300 2310);
DISPLAY 0.617021 (-6300 2310);
PAINT ORANGE (-6300 2310);
FORCEPROP 2 LASTPROP $XRERR UNIQUE?
J 0
(-6565 2300);
DISPLAY 0.638298 (-6565 2300);
PAINT MONO (-6565 2300);
DISPLAY INVISIBLE (-6565 2300);
WIRE 16 -1 (-5275 2450)(-6325 2450);
FORCEPROP 2 LAST SIG_NAME TP_CPU1_RSVD_270
J 0
(-6300 2460);
DISPLAY 0.617021 (-6300 2460);
PAINT ORANGE (-6300 2460);
FORCEPROP 2 LASTPROP $XRERR UNIQUE?
J 0
(-6565 2450);
DISPLAY 0.638298 (-6565 2450);
PAINT MONO (-6565 2450);
DISPLAY INVISIBLE (-6565 2450);
WIRE 16 -1 (-5275 3300)(-6325 3300);
FORCEPROP 2 LAST SIG_NAME TP_CPU1_RSVD_284
J 0
(-6300 3310);
DISPLAY 0.617021 (-6300 3310);
PAINT ORANGE (-6300 3310);
FORCEPROP 2 LASTPROP $XRERR UNIQUE?
J 0
(-6565 3300);
DISPLAY 0.638298 (-6565 3300);
PAINT MONO (-6565 3300);
DISPLAY INVISIBLE (-6565 3300);
WIRE 16 -1 (-5275 3550)(-6325 3550);
FORCEPROP 2 LAST SIG_NAME TP_CPU1_RSVD_289
J 0
(-6300 3560);
DISPLAY 0.617021 (-6300 3560);
PAINT ORANGE (-6300 3560);
FORCEPROP 2 LASTPROP $XRERR UNIQUE?
J 0
(-6565 3550);
DISPLAY 0.638298 (-6565 3550);
PAINT MONO (-6565 3550);
DISPLAY INVISIBLE (-6565 3550);
WIRE 16 -1 (-5275 3700)(-6325 3700);
FORCEPROP 2 LAST SIG_NAME TP_CPU1_RSVD_291
J 0
(-6300 3710);
DISPLAY 0.617021 (-6300 3710);
PAINT ORANGE (-6300 3710);
FORCEPROP 2 LASTPROP $XRERR UNIQUE?
J 0
(-6565 3700);
DISPLAY 0.638298 (-6565 3700);
PAINT MONO (-6565 3700);
DISPLAY INVISIBLE (-6565 3700);
WIRE 16 -1 (-5275 3800)(-6325 3800);
FORCEPROP 2 LAST SIG_NAME TP_CPU1_RSVD_293
J 0
(-6300 3810);
DISPLAY 0.617021 (-6300 3810);
PAINT ORANGE (-6300 3810);
FORCEPROP 2 LASTPROP $XRERR UNIQUE?
J 0
(-6565 3800);
DISPLAY 0.638298 (-6565 3800);
PAINT MONO (-6565 3800);
DISPLAY INVISIBLE (-6565 3800);
WIRE 16 -1 (-5275 3750)(-6325 3750);
FORCEPROP 2 LAST SIG_NAME TP_CPU1_RSVD_292
J 0
(-6300 3760);
DISPLAY 0.617021 (-6300 3760);
PAINT ORANGE (-6300 3760);
FORCEPROP 2 LASTPROP $XRERR UNIQUE?
J 0
(-6565 3750);
DISPLAY 0.638298 (-6565 3750);
PAINT MONO (-6565 3750);
DISPLAY INVISIBLE (-6565 3750);
WIRE 16 -1 (-5275 3650)(-6325 3650);
FORCEPROP 2 LAST SIG_NAME TP_CPU1_RSVD_290
J 0
(-6300 3660);
DISPLAY 0.617021 (-6300 3660);
PAINT ORANGE (-6300 3660);
FORCEPROP 2 LASTPROP $XRERR UNIQUE?
J 0
(-6565 3650);
DISPLAY 0.638298 (-6565 3650);
PAINT MONO (-6565 3650);
DISPLAY INVISIBLE (-6565 3650);
WIRE 16 -1 (-6325 1450)(-5275 1450);
FORCEPROP 2 LAST SIG_NAME TP_CPU1_RSVD_253
J 0
(-6300 1460);
DISPLAY 0.617021 (-6300 1460);
PAINT ORANGE (-6300 1460);
FORCEPROP 2 LASTPROP $XRERR UNIQUE?
J 0
(-6565 1450);
DISPLAY 0.638298 (-6565 1450);
PAINT MONO (-6565 1450);
DISPLAY INVISIBLE (-6565 1450);
WIRE 16 -1 (-6300 1500)(-5275 1500);
FORCEPROP 2 LAST SIG_NAME TP_CPU1_RSVD_254
J 0
(-6300 1510);
DISPLAY 0.617021 (-6300 1510);
PAINT ORANGE (-6300 1510);
FORCEPROP 2 LASTPROP $XRERR UNIQUE?
J 0
(-6540 1500);
DISPLAY 0.638298 (-6540 1500);
PAINT MONO (-6540 1500);
DISPLAY INVISIBLE (-6540 1500);
WIRE 16 -1 (-5275 1600)(-6325 1600);
FORCEPROP 2 LAST SIG_NAME TP_CPU1_RSVD_TEST_11
J 0
(-6300 1610);
DISPLAY 0.617021 (-6300 1610);
PAINT ORANGE (-6300 1610);
FORCEPROP 2 LASTPROP $XRERR UNIQUE?
J 0
(-6565 1600);
DISPLAY 0.638298 (-6565 1600);
PAINT MONO (-6565 1600);
DISPLAY INVISIBLE (-6565 1600);
WIRE 16 -1 (-6325 1850)(-5275 1850);
FORCEPROP 2 LAST SIG_NAME TP_CPU1_RSVD_259
J 0
(-6300 1860);
DISPLAY 0.617021 (-6300 1860);
PAINT ORANGE (-6300 1860);
FORCEPROP 2 LASTPROP $XRERR UNIQUE?
J 0
(-6565 1850);
DISPLAY 0.638298 (-6565 1850);
PAINT MONO (-6565 1850);
DISPLAY INVISIBLE (-6565 1850);
WIRE 16 -1 (-6325 1800)(-5275 1800);
FORCEPROP 2 LAST SIG_NAME TP_CPU1_RSVD_258
J 0
(-6300 1810);
DISPLAY 0.617021 (-6300 1810);
PAINT ORANGE (-6300 1810);
FORCEPROP 2 LASTPROP $XRERR UNIQUE?
J 0
(-6565 1800);
DISPLAY 0.638298 (-6565 1800);
PAINT MONO (-6565 1800);
DISPLAY INVISIBLE (-6565 1800);
WIRE 16 -1 (-6325 1700)(-5275 1700);
FORCEPROP 2 LAST SIG_NAME TP_CPU1_RSVD_256
J 0
(-6300 1710);
DISPLAY 0.617021 (-6300 1710);
PAINT ORANGE (-6300 1710);
FORCEPROP 2 LASTPROP $XRERR UNIQUE?
J 0
(-6565 1700);
DISPLAY 0.638298 (-6565 1700);
PAINT MONO (-6565 1700);
DISPLAY INVISIBLE (-6565 1700);
WIRE 16 -1 (-5275 2200)(-6325 2200);
FORCEPROP 2 LAST SIG_NAME TP_CPU1_RSVD_265
J 0
(-6300 2210);
DISPLAY 0.617021 (-6300 2210);
PAINT ORANGE (-6300 2210);
FORCEPROP 2 LASTPROP $XRERR UNIQUE?
J 0
(-6565 2200);
DISPLAY 0.638298 (-6565 2200);
PAINT MONO (-6565 2200);
DISPLAY INVISIBLE (-6565 2200);
WIRE 16 -1 (-5275 3100)(-6325 3100);
FORCEPROP 2 LAST SIG_NAME TP_CPU1_RSVD_281
J 0
(-6300 3110);
DISPLAY 0.617021 (-6300 3110);
PAINT ORANGE (-6300 3110);
FORCEPROP 2 LASTPROP $XRERR UNIQUE?
J 0
(-6565 3100);
DISPLAY 0.638298 (-6565 3100);
PAINT MONO (-6565 3100);
DISPLAY INVISIBLE (-6565 3100);
WIRE 16 -1 (-5275 3050)(-6325 3050);
FORCEPROP 2 LAST SIG_NAME TP_CPU1_RSVD_280
J 0
(-6300 3060);
DISPLAY 0.617021 (-6300 3060);
PAINT ORANGE (-6300 3060);
FORCEPROP 2 LASTPROP $XRERR UNIQUE?
J 0
(-6565 3050);
DISPLAY 0.638298 (-6565 3050);
PAINT MONO (-6565 3050);
DISPLAY INVISIBLE (-6565 3050);
WIRE 16 -1 (-5275 3000)(-6325 3000);
FORCEPROP 2 LAST SIG_NAME TP_CPU1_RSVD_279
J 0
(-6300 3010);
DISPLAY 0.617021 (-6300 3010);
PAINT ORANGE (-6300 3010);
FORCEPROP 2 LASTPROP $XRERR UNIQUE?
J 0
(-6565 3000);
DISPLAY 0.638298 (-6565 3000);
PAINT MONO (-6565 3000);
DISPLAY INVISIBLE (-6565 3000);
WIRE 16 -1 (-5275 2950)(-6325 2950);
FORCEPROP 2 LAST SIG_NAME TP_CPU1_RSVD_278
J 0
(-6300 2960);
DISPLAY 0.617021 (-6300 2960);
PAINT ORANGE (-6300 2960);
FORCEPROP 2 LASTPROP $XRERR UNIQUE?
J 0
(-6565 2950);
DISPLAY 0.638298 (-6565 2950);
PAINT MONO (-6565 2950);
DISPLAY INVISIBLE (-6565 2950);
WIRE 16 -1 (-5275 2850)(-6325 2850);
FORCEPROP 2 LAST SIG_NAME TP_CPU1_RSVD_277
J 0
(-6300 2860);
DISPLAY 0.617021 (-6300 2860);
PAINT ORANGE (-6300 2860);
FORCEPROP 2 LASTPROP $XRERR UNIQUE?
J 0
(-6565 2850);
DISPLAY 0.638298 (-6565 2850);
PAINT MONO (-6565 2850);
DISPLAY INVISIBLE (-6565 2850);
WIRE 16 -1 (-5275 2800)(-6325 2800);
FORCEPROP 2 LAST SIG_NAME TP_CPU1_RSVD_276
J 0
(-6300 2810);
DISPLAY 0.617021 (-6300 2810);
PAINT ORANGE (-6300 2810);
FORCEPROP 2 LASTPROP $XRERR UNIQUE?
J 0
(-6565 2800);
DISPLAY 0.638298 (-6565 2800);
PAINT MONO (-6565 2800);
DISPLAY INVISIBLE (-6565 2800);
WIRE 16 -1 (-5275 2700)(-6325 2700);
FORCEPROP 2 LAST SIG_NAME TP_CPU1_RSVD_275
J 0
(-6300 2710);
DISPLAY 0.617021 (-6300 2710);
PAINT ORANGE (-6300 2710);
FORCEPROP 2 LASTPROP $XRERR UNIQUE?
J 0
(-6565 2700);
DISPLAY 0.638298 (-6565 2700);
PAINT MONO (-6565 2700);
DISPLAY INVISIBLE (-6565 2700);
WIRE 16 -1 (-7050 1750)(-5275 1750);
FORCEPROP 2 LAST SIG_NAME FM_CPU1_RC_ERROR_N
J 0
(-7025 1760);
DISPLAY 0.617021 (-7025 1760);
PAINT ORANGE (-7025 1760);
WIRE 16 -1 (-5275 4300)(-6325 4300);
FORCEPROP 2 LAST SIG_NAME TP_CPU1_RSVD_303
J 0
(-6325 4310);
DISPLAY 0.617021 (-6325 4310);
PAINT ORANGE (-6325 4310);
FORCEPROP 2 LASTPROP $XRERR UNIQUE?
J 0
(-6565 4300);
DISPLAY 0.638298 (-6565 4300);
PAINT MONO (-6565 4300);
DISPLAY INVISIBLE (-6565 4300);
WIRE 16 -1 (-5275 4100)(-6325 4100);
FORCEPROP 2 LAST SIG_NAME TP_CPU1_RSVD_299
J 0
(-6300 4110);
DISPLAY 0.617021 (-6300 4110);
PAINT ORANGE (-6300 4110);
FORCEPROP 2 LASTPROP $XRERR UNIQUE?
J 0
(-6565 4100);
DISPLAY 0.638298 (-6565 4100);
PAINT MONO (-6565 4100);
DISPLAY INVISIBLE (-6565 4100);
WIRE 16 -1 (-5275 4150)(-6325 4150);
FORCEPROP 2 LAST SIG_NAME TP_CPU1_RSVD_300
J 0
(-6300 4160);
DISPLAY 0.617021 (-6300 4160);
PAINT ORANGE (-6300 4160);
FORCEPROP 2 LASTPROP $XRERR UNIQUE?
J 0
(-6565 4150);
DISPLAY 0.638298 (-6565 4150);
PAINT MONO (-6565 4150);
DISPLAY INVISIBLE (-6565 4150);
WIRE 16 -1 (-1600 2350)(-2775 2350);
FORCEPROP 2 LAST SIG_NAME TP_CPU1_RSVD_TEST_5
J 0
(-2175 2360);
DISPLAY 0.617021 (-2175 2360);
PAINT ORANGE (-2175 2360);
FORCEPROP 2 LASTPROP $XRERR UNIQUE?
J 0
(-1570 2350);
DISPLAY 0.638298 (-1570 2350);
PAINT MONO (-1570 2350);
DISPLAY INVISIBLE (-1570 2350);
WIRE 16 -1 (-1600 2250)(-2775 2250);
FORCEPROP 2 LAST SIG_NAME TP_CPU1_RSVD_216
J 0
(-2175 2260);
DISPLAY 0.617021 (-2175 2260);
PAINT ORANGE (-2175 2260);
FORCEPROP 2 LASTPROP $XRERR UNIQUE?
J 0
(-1570 2250);
DISPLAY 0.638298 (-1570 2250);
PAINT MONO (-1570 2250);
DISPLAY INVISIBLE (-1570 2250);
WIRE 16 -1 (-1600 1800)(-2775 1800);
FORCEPROP 2 LAST SIG_NAME TP_CPU1_RSVD_212
J 0
(-2175 1810);
DISPLAY 0.617021 (-2175 1810);
PAINT ORANGE (-2175 1810);
FORCEPROP 2 LASTPROP $XRERR UNIQUE?
J 0
(-1570 1800);
DISPLAY 0.638298 (-1570 1800);
PAINT MONO (-1570 1800);
DISPLAY INVISIBLE (-1570 1800);
WIRE 16 -1 (-1600 1750)(-2775 1750);
FORCEPROP 2 LAST SIG_NAME TP_CPU1_RSVD_211
J 0
(-2175 1760);
DISPLAY 0.617021 (-2175 1760);
PAINT ORANGE (-2175 1760);
FORCEPROP 2 LASTPROP $XRERR UNIQUE?
J 0
(-1570 1750);
DISPLAY 0.638298 (-1570 1750);
PAINT MONO (-1570 1750);
DISPLAY INVISIBLE (-1570 1750);
WIRE 16 -1 (-1600 1700)(-2775 1700);
FORCEPROP 2 LAST SIG_NAME TP_CPU1_RSVD_210
J 0
(-2175 1710);
DISPLAY 0.617021 (-2175 1710);
PAINT ORANGE (-2175 1710);
FORCEPROP 2 LASTPROP $XRERR UNIQUE?
J 0
(-1570 1700);
DISPLAY 0.638298 (-1570 1700);
PAINT MONO (-1570 1700);
DISPLAY INVISIBLE (-1570 1700);
WIRE 16 -1 (-1600 1550)(-2775 1550);
FORCEPROP 2 LAST SIG_NAME TP_CPU1_RSVD_208
J 0
(-2175 1560);
DISPLAY 0.617021 (-2175 1560);
PAINT ORANGE (-2175 1560);
FORCEPROP 2 LASTPROP $XRERR UNIQUE?
J 0
(-1570 1550);
DISPLAY 0.638298 (-1570 1550);
PAINT MONO (-1570 1550);
DISPLAY INVISIBLE (-1570 1550);
WIRE 16 -1 (-1600 2000)(-2775 2000);
FORCEPROP 2 LAST SIG_NAME TP_CPU1_RSVD_214
J 0
(-2175 2010);
DISPLAY 0.617021 (-2175 2010);
PAINT ORANGE (-2175 2010);
FORCEPROP 2 LASTPROP $XRERR UNIQUE?
J 0
(-1570 2000);
DISPLAY 0.638298 (-1570 2000);
PAINT MONO (-1570 2000);
DISPLAY INVISIBLE (-1570 2000);
WIRE 16 -1 (-1525 2500)(-2775 2500);
FORCEPROP 2 LAST SIG_NAME TP_CPU1_RSVD_217
J 0
(-2175 2510);
DISPLAY 0.617021 (-2175 2510);
PAINT ORANGE (-2175 2510);
FORCEPROP 2 LASTPROP $XRERR UNIQUE?
J 0
(-1495 2500);
DISPLAY 0.638298 (-1495 2500);
PAINT MONO (-1495 2500);
DISPLAY INVISIBLE (-1495 2500);
WIRE 16 -1 (-1525 2550)(-2775 2550);
FORCEPROP 2 LAST SIG_NAME TP_CPU1_RSVD_218
J 0
(-2175 2560);
DISPLAY 0.617021 (-2175 2560);
PAINT ORANGE (-2175 2560);
FORCEPROP 2 LASTPROP $XRERR UNIQUE?
J 0
(-1495 2550);
DISPLAY 0.638298 (-1495 2550);
PAINT MONO (-1495 2550);
DISPLAY INVISIBLE (-1495 2550);
WIRE 16 -1 (-1525 2600)(-2775 2600);
FORCEPROP 2 LAST SIG_NAME TP_CPU1_RSVD_219
J 0
(-2175 2610);
DISPLAY 0.617021 (-2175 2610);
PAINT ORANGE (-2175 2610);
FORCEPROP 2 LASTPROP $XRERR UNIQUE?
J 0
(-1495 2600);
DISPLAY 0.638298 (-1495 2600);
PAINT MONO (-1495 2600);
DISPLAY INVISIBLE (-1495 2600);
WIRE 16 -1 (-1600 3300)(-2775 3300);
FORCEPROP 2 LAST SIG_NAME TP_CPU1_RSVD_222
J 0
(-2175 3310);
DISPLAY 0.617021 (-2175 3310);
PAINT ORANGE (-2175 3310);
FORCEPROP 2 LASTPROP $XRERR UNIQUE?
J 0
(-1570 3300);
DISPLAY 0.638298 (-1570 3300);
PAINT MONO (-1570 3300);
DISPLAY INVISIBLE (-1570 3300);
WIRE 16 -1 (-1600 3350)(-2775 3350);
FORCEPROP 2 LAST SIG_NAME TP_CPU1_RSVD_223
J 0
(-2175 3360);
DISPLAY 0.617021 (-2175 3360);
PAINT ORANGE (-2175 3360);
FORCEPROP 2 LASTPROP $XRERR UNIQUE?
J 0
(-1570 3350);
DISPLAY 0.638298 (-1570 3350);
PAINT MONO (-1570 3350);
DISPLAY INVISIBLE (-1570 3350);
WIRE 16 -1 (-1600 3400)(-2775 3400);
FORCEPROP 2 LAST SIG_NAME TP_CPU1_RSVD_224
J 0
(-2175 3410);
DISPLAY 0.617021 (-2175 3410);
PAINT ORANGE (-2175 3410);
FORCEPROP 2 LASTPROP $XRERR UNIQUE?
J 0
(-1570 3400);
DISPLAY 0.638298 (-1570 3400);
PAINT MONO (-1570 3400);
DISPLAY INVISIBLE (-1570 3400);
WIRE 16 -1 (-1600 3450)(-2775 3450);
FORCEPROP 2 LAST SIG_NAME TP_CPU1_RSVD_225
J 0
(-2175 3460);
DISPLAY 0.617021 (-2175 3460);
PAINT ORANGE (-2175 3460);
FORCEPROP 2 LASTPROP $XRERR UNIQUE?
J 0
(-1570 3450);
DISPLAY 0.638298 (-1570 3450);
PAINT MONO (-1570 3450);
DISPLAY INVISIBLE (-1570 3450);
WIRE 16 -1 (-1600 3500)(-2775 3500);
FORCEPROP 2 LAST SIG_NAME TP_CPU1_RSVD_226
J 0
(-2175 3510);
DISPLAY 0.617021 (-2175 3510);
PAINT ORANGE (-2175 3510);
FORCEPROP 2 LASTPROP $XRERR UNIQUE?
J 0
(-1570 3500);
DISPLAY 0.638298 (-1570 3500);
PAINT MONO (-1570 3500);
DISPLAY INVISIBLE (-1570 3500);
WIRE 16 -1 (-1600 3550)(-2775 3550);
FORCEPROP 2 LAST SIG_NAME TP_CPU1_RSVD_227
J 0
(-2175 3560);
DISPLAY 0.617021 (-2175 3560);
PAINT ORANGE (-2175 3560);
FORCEPROP 2 LASTPROP $XRERR UNIQUE?
J 0
(-1570 3550);
DISPLAY 0.638298 (-1570 3550);
PAINT MONO (-1570 3550);
DISPLAY INVISIBLE (-1570 3550);
WIRE 16 -1 (-1600 3650)(-2775 3650);
FORCEPROP 2 LAST SIG_NAME TP_CPU1_RSVD_228
J 0
(-2175 3660);
DISPLAY 0.617021 (-2175 3660);
PAINT ORANGE (-2175 3660);
FORCEPROP 2 LASTPROP $XRERR UNIQUE?
J 0
(-1570 3650);
DISPLAY 0.638298 (-1570 3650);
PAINT MONO (-1570 3650);
DISPLAY INVISIBLE (-1570 3650);
WIRE 16 -1 (-1600 3700)(-2775 3700);
FORCEPROP 2 LAST SIG_NAME TP_CPU1_RSVD_229
J 0
(-2175 3710);
DISPLAY 0.617021 (-2175 3710);
PAINT ORANGE (-2175 3710);
FORCEPROP 2 LASTPROP $XRERR UNIQUE?
J 0
(-1570 3700);
DISPLAY 0.638298 (-1570 3700);
PAINT MONO (-1570 3700);
DISPLAY INVISIBLE (-1570 3700);
WIRE 16 -1 (-1600 3750)(-2775 3750);
FORCEPROP 2 LAST SIG_NAME TP_CPU1_RSVD_230
J 0
(-2175 3760);
DISPLAY 0.617021 (-2175 3760);
PAINT ORANGE (-2175 3760);
FORCEPROP 2 LASTPROP $XRERR UNIQUE?
J 0
(-1570 3750);
DISPLAY 0.638298 (-1570 3750);
PAINT MONO (-1570 3750);
DISPLAY INVISIBLE (-1570 3750);
WIRE 16 -1 (-1600 3800)(-2775 3800);
FORCEPROP 2 LAST SIG_NAME TP_CPU1_RSVD_231
J 0
(-2175 3810);
DISPLAY 0.617021 (-2175 3810);
PAINT ORANGE (-2175 3810);
FORCEPROP 2 LASTPROP $XRERR UNIQUE?
J 0
(-1570 3800);
DISPLAY 0.638298 (-1570 3800);
PAINT MONO (-1570 3800);
DISPLAY INVISIBLE (-1570 3800);
WIRE 16 -1 (-1600 3850)(-2775 3850);
FORCEPROP 2 LAST SIG_NAME TP_CPU1_RSVD_232
J 0
(-2175 3860);
DISPLAY 0.617021 (-2175 3860);
PAINT ORANGE (-2175 3860);
FORCEPROP 2 LASTPROP $XRERR UNIQUE?
J 0
(-1570 3850);
DISPLAY 0.638298 (-1570 3850);
PAINT MONO (-1570 3850);
DISPLAY INVISIBLE (-1570 3850);
WIRE 16 -1 (-1600 3900)(-2775 3900);
FORCEPROP 2 LAST SIG_NAME TP_CPU1_RSVD_233
J 0
(-2175 3910);
DISPLAY 0.617021 (-2175 3910);
PAINT ORANGE (-2175 3910);
FORCEPROP 2 LASTPROP $XRERR UNIQUE?
J 0
(-1570 3900);
DISPLAY 0.638298 (-1570 3900);
PAINT MONO (-1570 3900);
DISPLAY INVISIBLE (-1570 3900);
WIRE 16 -1 (-1600 3950)(-2775 3950);
FORCEPROP 2 LAST SIG_NAME TP_CPU1_RSVD_234
J 0
(-2175 3960);
DISPLAY 0.617021 (-2175 3960);
PAINT ORANGE (-2175 3960);
FORCEPROP 2 LASTPROP $XRERR UNIQUE?
J 0
(-1570 3950);
DISPLAY 0.638298 (-1570 3950);
PAINT MONO (-1570 3950);
DISPLAY INVISIBLE (-1570 3950);
WIRE 16 -1 (-1600 4050)(-2775 4050);
FORCEPROP 2 LAST SIG_NAME TP_CPU1_RSVD_235
J 0
(-2175 4060);
DISPLAY 0.617021 (-2175 4060);
PAINT ORANGE (-2175 4060);
FORCEPROP 2 LASTPROP $XRERR UNIQUE?
J 0
(-1570 4050);
DISPLAY 0.638298 (-1570 4050);
PAINT MONO (-1570 4050);
DISPLAY INVISIBLE (-1570 4050);
WIRE 16 -1 (-1600 800)(-2775 800);
FORCEPROP 2 LAST SIG_NAME TP_CPU1_RSVD_194
J 0
(-2175 810);
DISPLAY 0.617021 (-2175 810);
PAINT ORANGE (-2175 810);
FORCEPROP 2 LASTPROP $XRERR UNIQUE?
J 0
(-1570 800);
DISPLAY 0.638298 (-1570 800);
PAINT MONO (-1570 800);
DISPLAY INVISIBLE (-1570 800);
WIRE 16 -1 (-1600 1000)(-2775 1000);
FORCEPROP 2 LAST SIG_NAME TP_CPU1_RSVD_198
J 0
(-2175 1010);
DISPLAY 0.617021 (-2175 1010);
PAINT ORANGE (-2175 1010);
FORCEPROP 2 LASTPROP $XRERR UNIQUE?
J 0
(-1570 1000);
DISPLAY 0.638298 (-1570 1000);
PAINT MONO (-1570 1000);
DISPLAY INVISIBLE (-1570 1000);
WIRE 16 -1 (-1600 1050)(-2775 1050);
FORCEPROP 2 LAST SIG_NAME TP_CPU1_RSVD_199
J 0
(-2175 1060);
DISPLAY 0.617021 (-2175 1060);
PAINT ORANGE (-2175 1060);
FORCEPROP 2 LASTPROP $XRERR UNIQUE?
J 0
(-1570 1050);
DISPLAY 0.638298 (-1570 1050);
PAINT MONO (-1570 1050);
DISPLAY INVISIBLE (-1570 1050);
WIRE 16 -1 (-1600 1350)(-2775 1350);
FORCEPROP 2 LAST SIG_NAME TP_CPU1_RSVD_204
J 0
(-2175 1360);
DISPLAY 0.617021 (-2175 1360);
PAINT ORANGE (-2175 1360);
FORCEPROP 2 LASTPROP $XRERR UNIQUE?
J 0
(-1570 1350);
DISPLAY 0.638298 (-1570 1350);
PAINT MONO (-1570 1350);
DISPLAY INVISIBLE (-1570 1350);
WIRE 16 -1 (-1600 1400)(-2775 1400);
FORCEPROP 2 LAST SIG_NAME TP_CPU1_RSVD_205
J 0
(-2175 1410);
DISPLAY 0.617021 (-2175 1410);
PAINT ORANGE (-2175 1410);
FORCEPROP 2 LASTPROP $XRERR UNIQUE?
J 0
(-1570 1400);
DISPLAY 0.638298 (-1570 1400);
PAINT MONO (-1570 1400);
DISPLAY INVISIBLE (-1570 1400);
WIRE 16 -1 (-1550 2950)(-2775 2950);
FORCEPROP 2 LAST SIG_NAME TP_CPU1_RSVD_TEST_4
J 0
(-2350 2960);
DISPLAY 0.617021 (-2350 2960);
PAINT ORANGE (-2350 2960);
FORCEPROP 2 LASTPROP $XRERR UNIQUE?
J 0
(-1520 2950);
DISPLAY 0.638298 (-1520 2950);
PAINT MONO (-1520 2950);
DISPLAY INVISIBLE (-1520 2950);
WIRE 16 -1 (-1550 3000)(-2775 3000);
FORCEPROP 2 LAST SIG_NAME TP_CPU1_RSVD_TEST_3
J 0
(-2350 3010);
DISPLAY 0.617021 (-2350 3010);
PAINT ORANGE (-2350 3010);
FORCEPROP 2 LASTPROP $XRERR UNIQUE?
J 0
(-1520 3000);
DISPLAY 0.638298 (-1520 3000);
PAINT MONO (-1520 3000);
DISPLAY INVISIBLE (-1520 3000);
WIRE 16 -1 (-1625 2850)(-2775 2850);
FORCEPROP 2 LAST SIG_NAME XDP_CPU_PWR_DEBUG_N
J 0
(-2225 2860);
DISPLAY 0.617021 (-2225 2860);
PAINT ORANGE (-2225 2860);
WIRE 16 -1 (-1600 2450)(-2775 2450);
FORCEPROP 2 LAST SIG_NAME XDP_PRESENT_N
J 0
(-2175 2460);
DISPLAY 0.617021 (-2175 2460);
PAINT ORANGE (-2175 2460);
WIRE 16 -1 (-1500 1450)(-2775 1450);
FORCEPROP 2 LAST SIG_NAME CLK_100M_CPU1_RC_REFCLK0_DP
J 0
(-2275 1460);
DISPLAY 0.617021 (-2275 1460);
PAINT ORANGE (-2275 1460);
WIRE 16 -1 (-1500 850)(-2775 850);
FORCEPROP 2 LAST SIG_NAME CLK_100M_CPU1_RC_REFCLK0_DN
J 0
(-2275 860);
DISPLAY 0.617021 (-2275 860);
PAINT ORANGE (-2275 860);
WIRE 16 -1 (-1500 1850)(-2775 1850);
FORCEPROP 2 LAST SIG_NAME CLK_322M_OSC_CPU1_RC_DN
J 0
(-2285 1860);
DISPLAY 0.617021 (-2285 1860);
PAINT ORANGE (-2285 1860);
WIRE 16 -1 (-1500 2050)(-2775 2050);
FORCEPROP 2 LAST SIG_NAME PD_CPU1_DMIMODE_OVERRIDE
J 0
(-2200 2060);
DISPLAY 0.617021 (-2200 2060);
PAINT ORANGE (-2200 2060);
WIRE 16 -1 (-1625 2700)(-2775 2700);
FORCEPROP 2 LAST SIG_NAME CLK_322M_OSC_CPU1_RC_DP
J 0
(-2285 2710);
DISPLAY 0.617021 (-2285 2710);
PAINT ORANGE (-2285 2710);
WIRE 16 -1 (-1600 2650)(-2775 2650);
FORCEPROP 2 LAST SIG_NAME H_CPU1_FIVR_FAULT_G
J 0
(-2200 2660);
DISPLAY 0.617021 (-2200 2660);
PAINT ORANGE (-2200 2660);
WIRE 16 -1 (-2775 3250)(-1500 3250);
FORCEPROP 2 LAST SIG_NAME VSENSE_P1V8MCP_CPU1_SKT_VSEN
J 0
(-2452 3258);
DISPLAY 0.617021 (-2452 3258);
PAINT ORANGE (-2452 3258);
WIRE 16 -1 (-2775 2200)(-1575 2200);
FORCEPROP 2 LAST SIG_NAME VSENSE_P1V8MCP_CPU1_SKT_VRTN
J 0
(-2452 2208);
DISPLAY 0.617021 (-2452 2208);
PAINT ORANGE (-2452 2208);
WIRE 16 -1 (-550 2850)(-550 3050);
WIRE 16 -1 (-550 3050)(-2775 3050);
FORCEPROP 2 LAST SIG_NAME PD_CPU1_RSVD_TEST_2
J 0
(-2350 3060);
DISPLAY 0.617021 (-2350 3060);
PAINT ORANGE (-2350 3060);
FORCEPROP 2 LASTPROP $XRERR UNIQUE?
J 0
(-2590 3060);
DISPLAY 0.638298 (-2590 3060);
PAINT MONO (-2590 3060);
DISPLAY INVISIBLE (-2590 3060);
WIRE 16 -1 (-275 2850)(-275 3100);
WIRE 16 -1 (-275 3100)(-2775 3100);
FORCEPROP 2 LAST SIG_NAME PD_CPU1_RSVD_TEST_1
J 0
(-2350 3110);
DISPLAY 0.617021 (-2350 3110);
PAINT ORANGE (-2350 3110);
FORCEPROP 2 LASTPROP $XRERR UNIQUE?
J 0
(-2590 3110);
DISPLAY 0.638298 (-2590 3110);
PAINT MONO (-2590 3110);
DISPLAY INVISIBLE (-2590 3110);
WIRE 16 -1 (-1600 4100)(-2775 4100);
FORCEPROP 2 LAST SIG_NAME TP_CPU1_RSVD_236
J 0
(-2175 4110);
DISPLAY 0.617021 (-2175 4110);
PAINT ORANGE (-2175 4110);
FORCEPROP 2 LASTPROP $XRERR UNIQUE?
J 0
(-1570 4100);
DISPLAY 0.638298 (-1570 4100);
PAINT MONO (-1570 4100);
DISPLAY INVISIBLE (-1570 4100);
WIRE 16 -1 (-1600 4150)(-2775 4150);
FORCEPROP 2 LAST SIG_NAME TP_CPU1_RSVD_237
J 0
(-2175 4160);
DISPLAY 0.617021 (-2175 4160);
PAINT ORANGE (-2175 4160);
FORCEPROP 2 LASTPROP $XRERR UNIQUE?
J 0
(-1570 4150);
DISPLAY 0.638298 (-1570 4150);
PAINT MONO (-1570 4150);
DISPLAY INVISIBLE (-1570 4150);
WIRE 16 -1 (-1600 4200)(-2775 4200);
FORCEPROP 2 LAST SIG_NAME TP_CPU1_RSVD_238
J 0
(-2175 4210);
DISPLAY 0.617021 (-2175 4210);
PAINT ORANGE (-2175 4210);
FORCEPROP 2 LASTPROP $XRERR UNIQUE?
J 0
(-1570 4200);
DISPLAY 0.638298 (-1570 4200);
PAINT MONO (-1570 4200);
DISPLAY INVISIBLE (-1570 4200);
WIRE 16 -1 (-1600 4250)(-2775 4250);
FORCEPROP 2 LAST SIG_NAME TP_CPU1_RSVD_239
J 0
(-2175 4260);
DISPLAY 0.617021 (-2175 4260);
PAINT ORANGE (-2175 4260);
FORCEPROP 2 LASTPROP $XRERR UNIQUE?
J 0
(-1570 4250);
DISPLAY 0.638298 (-1570 4250);
PAINT MONO (-1570 4250);
DISPLAY INVISIBLE (-1570 4250);
WIRE 16 -1 (-1600 4300)(-2775 4300);
FORCEPROP 2 LAST SIG_NAME TP_CPU1_RSVD_240
J 0
(-2175 4310);
DISPLAY 0.617021 (-2175 4310);
PAINT ORANGE (-2175 4310);
FORCEPROP 2 LASTPROP $XRERR UNIQUE?
J 0
(-1570 4300);
DISPLAY 0.638298 (-1570 4300);
PAINT MONO (-1570 4300);
DISPLAY INVISIBLE (-1570 4300);
WIRE 16 -1 (-1600 4350)(-2775 4350);
FORCEPROP 2 LAST SIG_NAME TP_CPU1_RSVD_241
J 0
(-2175 4360);
DISPLAY 0.617021 (-2175 4360);
PAINT ORANGE (-2175 4360);
FORCEPROP 2 LASTPROP $XRERR UNIQUE?
J 0
(-1570 4350);
DISPLAY 0.638298 (-1570 4350);
PAINT MONO (-1570 4350);
DISPLAY INVISIBLE (-1570 4350);
DOT 1 (-950 1650);
DOT 1 (-950 1100);
DOT 1 (-950 1500);
DOT 1 (-5450 3900);
DOT 1 (-5450 3950);
DOT 1 (-7250 4250);
DOT 1 (-5450 4250);
DOT 1 (-275 2525);
DOT 1 (-2575 900);
DOT 1 (-2550 1100);
DOT 1 (-2550 1150);
DOT 1 (-2550 1200);
FORCENOTE
BOM_COST=PROC_SOCKET
(-7925 225) 0;
DISPLAY LEFT (-7925 225);
DISPLAY 1.723404 (-7925 225);
PAINT PURPLE (-7925 225);
FORCENOTE
ROOM=CPU1
(-7925 350) 0;
DISPLAY LEFT (-7925 350);
DISPLAY 1.723404 (-7925 350);
PAINT PURPLE (-7925 350);
QUIT
